M48
INCH,TZ
T01C.001
T02C.008
T03C.01
T04C.01
T05C.012
T06C.012
T07C.015
T08C.01574
T09C.016
T10C.018
T11C.01968
T12C.022
T13C.024
T14C.026
T15C.02952
T16C.03
T17C.03
T18C.031
T19C.032
T20C.034
T21C.036
T22C.039
T23C.04
T24C.04
T25C.041
T26C.041
T27C.045
T28C.046
T29C.049
T30C.096
T31C.125
T32C.177
T33C.224
T34C.022
T35C.026
T36C.03
T37C.03
T38C.032
T39C.036
T40C.039
T41C.04
T42C.041
T43C.044
T44C.046
T45C.047
T46C.05
T47C.05
T48C.054
T49C.059
T50C.063
T51C.065
T52C.084
T53C.086
T54C.087
T55C.125
T56C.15
;LEADER: 12 
;HEADER: 
;CODE  : ASCII 
;FILE  : 15126-1b-1-14.drl for board D:/<user>/15126-1b/gerber/#Taaaavn08468.tmp ... layers TOP and BOTTOM
;T01 Holesize 1. = 1.000000 Tolerance = +0.000000/-0.000000 PLATED MILS Quantity = 2
;T02 Holesize 2. = 8.000000 Tolerance = +0.000000/-0.000000 PLATED MILS Quantity = 1212
;T03 Holesize 3. = 10.000000 Tolerance = +0.000000/-0.000000 PLATED MILS Quantity = 21153
;T04 Holesize 4. = 10.000000 Tolerance = +4.000000/-10.000000 PLATED MILS Quantity = 1839
;T05 Holesize 5. = 12.000000 Tolerance = +0.000000/-0.000000 PLATED MILS Quantity = 3920
;T06 Holesize 6. = 12.000000 Tolerance = +3.000000/-3.000000 PLATED MILS Quantity = 7
;T07 Holesize 7. = 15.000000 Tolerance = +2.000000/-2.000000 PLATED MILS Quantity = 72
;T08 Holesize 8. = 15.740000 Tolerance = +0.000000/-0.000000 PLATED MILS Quantity = 96
;T09 Holesize 9. = 16.000000 Tolerance = +0.000000/-0.000000 PLATED MILS Quantity = 135 (SuppressedHoles = 44)
;T10 Holesize 10. = 18.000000 Tolerance = +0.000000/-0.000000 PLATED MILS Quantity = 2
;T11 Holesize 11. = 19.680000 Tolerance = +0.000000/-0.000000 PLATED MILS Quantity = 56
;T12 Holesize 12. = 22.000000 Tolerance = +0.000000/-0.000000 PLATED MILS Quantity = 12 (SuppressedHoles = 6)
;T13 Holesize 13. = 24.000000 Tolerance = +3.000000/-3.000000 PLATED MILS Quantity = 8
;T14 Holesize 14. = 26.000000 Tolerance = +0.000000/-0.000000 PLATED MILS Quantity = 14 (SuppressedHoles = 7)
;T15 Holesize 15. = 29.520000 Tolerance = +0.000000/-0.000000 PLATED MILS Quantity = 24
;T16 Holesize 16. = 30.000000 Tolerance = +0.000000/-0.000000 PLATED MILS Quantity = 6
;T17 Holesize 17. = 30.000000 Tolerance = +3.000000/-3.000000 PLATED MILS Quantity = 9
;T18 Holesize 18. = 31.000000 Tolerance = +0.000000/-0.000000 PLATED MILS Quantity = 6
;T19 Holesize 19. = 32.000000 Tolerance = +3.000000/-3.000000 PLATED MILS Quantity = 4
;T20 Holesize 20. = 34.000000 Tolerance = +0.000000/-0.000000 PLATED MILS Quantity = 2
;T21 Holesize 21. = 36.000000 Tolerance = +0.000000/-0.000000 PLATED MILS Quantity = 111
;T22 Holesize 22. = 39.000000 Tolerance = +3.000000/-3.000000 PLATED MILS Quantity = 3
;T23 Holesize 23. = 40.000000 Tolerance = +0.000000/-0.000000 PLATED MILS Quantity = 3
;T24 Holesize 24. = 40.000000 Tolerance = +3.000000/-3.000000 PLATED MILS Quantity = 14
;T25 Holesize 25. = 41.000000 Tolerance = +0.000000/-0.000000 PLATED MILS Quantity = 96
;T26 Holesize 26. = 41.000000 Tolerance = +3.000000/-3.000000 PLATED MILS Quantity = 2
;T27 Holesize 27. = 45.000000 Tolerance = +3.000000/-3.000000 PLATED MILS Quantity = 12
;T28 Holesize 28. = 46.000000 Tolerance = +0.000000/-0.000000 PLATED MILS Quantity = 8
;T29 Holesize 29. = 49.000000 Tolerance = +3.000000/-3.000000 PLATED MILS Quantity = 44
;T30 Holesize 30. = 96.000000 Tolerance = +3.000000/-3.000000 PLATED MILS Quantity = 48
;T31 Holesize 31. = 125.000000 Tolerance = +5.000000/-5.000000 PLATED MILS Quantity = 3
;T32 Holesize 32. = 177.000000 Tolerance = +4.000000/-4.000000 PLATED MILS Quantity = 1
;T33 Holesize 33. = 224.000000 Tolerance = +0.000000/-0.000000 PLATED MILS Quantity = 1
;T34 Holesize 34. = 22.000000 Tolerance = +3.000000/-3.000000 NON_PLATED MILS Quantity = 2
;T35 Holesize 35. = 26.000000 Tolerance = +0.000000/-0.000000 NON_PLATED MILS Quantity = 1
;T36 Holesize 36. = 30.000000 Tolerance = +0.000000/-0.000000 NON_PLATED MILS Quantity = 1
;T37 Holesize 37. = 30.000000 Tolerance = +3.000000/-3.000000 NON_PLATED MILS Quantity = 2
;T38 Holesize 38. = 32.000000 Tolerance = +3.000000/-3.000000 NON_PLATED MILS Quantity = 2
;T39 Holesize 39. = 36.000000 Tolerance = +0.000000/-0.000000 NON_PLATED MILS Quantity = 2
;T40 Holesize 40. = 39.000000 Tolerance = +1.000000/-1.000000 NON_PLATED MILS Quantity = 2
;T41 Holesize 41. = 40.000000 Tolerance = +3.000000/-3.000000 NON_PLATED MILS Quantity = 3
;T42 Holesize 42. = 41.000000 Tolerance = +3.000000/-3.000000 NON_PLATED MILS Quantity = 2
;T43 Holesize 43. = 44.000000 Tolerance = +0.000000/-0.000000 NON_PLATED MILS Quantity = 1
;T44 Holesize 44. = 46.000000 Tolerance = +0.000000/-0.000000 NON_PLATED MILS Quantity = 2
;T45 Holesize 45. = 47.000000 Tolerance = +3.000000/-3.000000 NON_PLATED MILS Quantity = 2
;T46 Holesize 46. = 50.000000 Tolerance = +0.000000/-0.000000 NON_PLATED MILS Quantity = 2
;T47 Holesize 47. = 50.000000 Tolerance = +3.000000/-3.000000 NON_PLATED MILS Quantity = 10
;T48 Holesize 48. = 54.000000 Tolerance = +3.000000/-3.000000 NON_PLATED MILS Quantity = 1
;T49 Holesize 49. = 59.000000 Tolerance = +3.000000/-3.000000 NON_PLATED MILS Quantity = 1
;T50 Holesize 50. = 63.000000 Tolerance = +0.000000/-0.000000 NON_PLATED MILS Quantity = 1
;T51 Holesize 51. = 65.000000 Tolerance = +0.000000/-0.000000 NON_PLATED MILS Quantity = 4
;T52 Holesize 52. = 84.000000 Tolerance = +0.000000/-0.000000 NON_PLATED MILS Quantity = 2
;T53 Holesize 53. = 86.000000 Tolerance = +0.000000/-0.000000 NON_PLATED MILS Quantity = 5
;T54 Holesize 54. = 87.000000 Tolerance = +3.000000/-3.000000 NON_PLATED MILS Quantity = 5
;T55 Holesize 55. = 125.000000 Tolerance = +2.000000/-2.000000 NON_PLATED MILS Quantity = 6
;T56 Holesize 56. = 150.000000 Tolerance = +0.000000/-0.000000 NON_PLATED MILS Quantity = 14
%
G90
T01
X1950000Y207893
Y241555
T02
X311021Y9114
X317714
X324407
X327754
X334446
X337793
X344486Y9122
X347833
X354525
X307675Y17057
X314368
X321061
X324407
X331100
X334447
X341140
X344486
X351179
X354526
X307675Y28014
X314368
X321061
X324407
X331100
X334446
X341140Y28022
X344486
X351179
X354525
X311021Y35957
X317714
X324407
X327754
X334447
X337793
X344486
X347833
X354526
X311021Y46914
X317714
X324407
X327754
X334446
X337793
X344486Y46922
X347833
X354525
X307675Y54857
X314368
X321061
X324407
X331100
X334447
X341140
X344486
X351179
X354526
X314368Y65814
X321061
X324407
X331100
X334446
X341140Y65822
X344486
X351179
X354525
X307928Y67802
X317714Y73757
X324407
X327754
X334447
X337793
X344486
X347833
X354526
X330948Y201258
X320784Y203219
X308198Y528863
X321061Y529014
X324407
X331100
X334446
X341140Y529022
X344486
X351179
X354525
X311021Y536957
X317714
X324407
X327754
X334447
X337793
X344486
X347833
X354526
X311021Y547914
X317714
X324407
X327754
X334446
X337793
X344486Y547922
X347833
X354525
X307675Y555857
X314368
X321061
X324407
X331100
X334447
X341140
X344486
X351179
X354526
X307984Y566743
X314368Y566814
X321061
X324407
X331100
X334446
X341140Y566822
X344486
X351179
X354525
X311021Y574757
X317714
X324407
X327754
X334447
X337793
X344486
X347833
X354526
X311021Y585714
X317714
X324407
X327754
X334446
X337793
X344486Y585722
X347833
X354525
X307675Y593657
X314368
X321061
X324407
X331100
X334447
X341140
X344486
X351179
X354526
X414763
X404723
X408069Y593642
X398029
X414763Y585722
X411416
X404723
X401377
X414763Y574757
X411416
X404723
X401377
X394684
X414763Y566822
X411416
X404723
X401377
X414763Y555857
X404723
X408069Y555842
X398029
X414763Y547922
X411415Y547921
X404723Y547922
X401376
X414763Y536957
X411416
X404723
X401377
X411416Y529022
X404723
X401377
X414763Y73757
X411416
X404723
X401377
X414763Y65822
X411416
X404723
X401377
X414763Y54857
X404723
X408069Y54842
X398029
X414763Y46922
X411416
X404723
X401377
X364265Y46914
X361518
X411415Y36058
X414763Y35957
X404723
X401377
X394684
X414762Y28021
X411416Y28022
X404723
X401377
X364565Y28014
X361218
X414762Y17058
X404723Y17057
X408069Y17042
X398029
X414763Y9122
X411416
X404722Y9121
X401376
X421455
X428147Y9120
X434840
X438187
X444880Y9122
X424801Y17042
X431494
X421456Y17057
X438187Y17059
X444880
X421456Y28022
X428149
X438189
X444880
X434842Y28268
X421456Y35957
X428149
X434842
X438189
X444882
X421455Y46921
X428149Y46922
X434842
X438189
X444880
X424801Y54842
X431494
X421456Y54857
X438187Y54859
X444880
X421456Y65822
X428149
X434842
X438189
X444880
X421456Y73757
X428149
X434842
X438189
X458640Y200596
X421456Y529022
X428149
X434842
X428149Y536957
X434842
X438189
X444882
X421456Y547922
X428149
X434842
X438189
X444880
X424801Y555842
X431494
X421456Y555857
X438187Y555859
X444880
X421456Y566822
X428149
X434842
X438189
X444880
X428149Y574757
X434842
X438189
X444882
X421456Y585722
X428149
X434842
X438189
X444880
X424801Y593642
X431494
X421456Y593657
X438187Y593659
X444880
X957283Y593657
X957592Y566743
X957283Y555857
X957806Y528863
X957536Y67802
X957283Y54857
Y28014
Y17057
X960629Y9114
X967322
X974015
X977362
X984054
X987401
X994094Y9122
X997441
X1004133
X963976Y17057
X970669
X974015
X980708
X984055
X990748
X994094
X1000787
X1004134
X963976Y28014
X970669
X974015
X980708
X984054
X990748Y28022
X994094
X1000787
X1004133
X960629Y35957
X967322
X974015
X977362
X984055
X987401
X994094
X997441
X1004134
X960629Y46914
X967322
X974015
X977362
X984054
X987401
X994094Y46922
X997441
X1004133
X963976Y54857
X970669
X974015
X980708
X984055
X990748
X994094
X1000787
X1004134
X963976Y65814
X970669
X974015
X980708
X984054
X990748Y65822
X994094
X1000787
X1004133
X967322Y73757
X974015
X977362
X984055
X987401
X994094
X997441
X1004134
X980556Y201258
X970392Y203219
X970669Y529014
X974015
X980708
X984054
X990748Y529022
X994094
X1000787
X1004133
X960629Y536957
X967322
X974015
X977362
X984055
X987401
X994094
X997441
X1004134
X960629Y547914
X967322
X974015
X977362
X984054
X987401
X994094Y547922
X997441
X1004133
X963976Y555857
X970669
X974015
X980708
X984055
X990748
X994094
X1000787
X1004134
X963976Y566814
X970669
X974015
X980708
X984054
X990748Y566822
X994094
X1000787
X1004133
X960629Y574757
X967322
X974015
X977362
X984055
X987401
X994094
X997441
X1004134
X960629Y585714
X967322
X974015
X977362
X984054
X987401
X994094Y585722
X997441
X1004133
X963976Y593657
X970669
X974015
X980708
X984055
X990748
X994094
X1000787
X1004134
X1071064
X1064371
X1054331
X1057677Y593642
X1047637
X1077757Y585722
X1071064
X1064371
X1061024
X1054331
X1050985
X1077757Y574757
X1071064
X1064371
X1061024
X1054331
X1050985
X1044292
X1077757Y566822
X1071064
X1064371
X1061024
X1054331
X1050985
X1071064Y555857
X1064371
X1054331
X1074409Y555842
X1057677
X1047637
X1077757Y547922
X1071064
X1067716Y547907
X1064371Y547922
X1061024
X1054331
X1050984
X1077757Y536957
X1064371
X1061024
X1054331
X1050985
X1077757Y529022
X1071064
X1061024
X1054331
X1050985
X1077757Y73757
X1071064
X1064371
X1061024
X1054331
X1050985
X1077757Y65822
X1071064
X1064371
X1061024
X1054331
X1050985
X1071064Y54857
X1064371
X1054331
X1074409Y54842
X1057677
X1047637
X1077757Y46922
X1071064
X1064371
X1061024
X1054331
X1050985
X1077757Y35957
X1071064
X1064371
X1061024
X1054331
X1050985
X1044292
X1077757Y28022
X1071064
X1064371
X1061024
X1054331
X1050985
X1071064Y17057
X1064371
X1054331
X1074409Y17042
X1057677
X1047637
X1077757Y9122
X1071064
X1064371
X1061024
X1054331
X1050985
X1084450
X1087797
X1094488
X1081102Y17042
X1087795Y17059
X1094488
X1087797Y28022
X1094488
X1084450Y28098
Y35957
X1087797
X1094490
X1084450Y46922
X1087797
X1094488
X1081102Y54842
X1087795Y54859
X1094488
X1084450Y65822
X1087797
X1094488
X1084450Y73757
X1087797
X1111631Y198327
X1108248Y200596
X1084450Y529022
Y536957
X1087797
X1094490
X1084450Y547922
X1087797
X1094488
X1081102Y555842
X1087795Y555859
X1094488
X1084450Y566822
X1087797
X1094488
X1084450Y574757
X1087797
X1094490
X1084450Y585722
X1087797
X1094488
X1081102Y593642
X1087795Y593659
X1094488
X1463610Y321329
X1478524Y318900
X1458400Y318500
X1462776Y318200
X1445528Y317772
X1489546Y317696
X1486396
X1454928Y317723
X1451753Y317696
X1448603
X1440910Y316693
X1495699Y314546
X1492696
X1489546
X1486397
X1483247
X1480098
X1473798
X1470649
X1461202
X1458052
X1454902
X1451753
X1448603
X1495651Y311350
X1492700Y311376
X1489546Y311397
X1486397
X1483247
X1480098
X1476948
X1473798
X1470649
X1464351
X1461202
X1458052
X1454902
X1451753
X1448603
X1445454
X1442304
X1489546Y308247
X1486397
X1483247
X1480098
X1476948
X1473798
X1470649
X1464350
X1458052
X1454902
X1448603
X1445454
X1442304
X1486397Y305098
X1483247
X1480098
X1476948
X1473798
X1470649
X1464351
X1461202
X1458052
X1454902
X1451753
X1448603
X1445454
X1442304
X1493500Y304400
X1497509Y303120
X1489546Y301948
X1486397
X1483247
X1480098
X1476949Y301949
X1473798Y301948
X1470649
X1464351
X1461202
X1458051Y301949
X1454902Y301948
X1451753
X1448603
X1445454
X1493400Y300800
X1486397Y298798
X1483247
X1480098
X1476948
X1473798
X1470649
X1464351
X1461202
X1458052
X1454902
X1451753
X1448603
X1445454
X1442303Y298799
X1495300Y297300
X1486397Y295649
X1480098
X1476948
X1473798
X1470649
X1464351
X1461202
X1458052
X1454902
X1451751
X1448577Y295624
X1445427
X1454751Y292651
X1445427Y292526
X1442304Y292499
X1483247Y289351
X1476948
X1473798
X1470649
X1464351
X1461202
X1458052
X1454902
X1451753
X1448603
X1445454
X1442304Y289350
X1489546Y286202
X1486397
X1483247
X1480098
X1476948
X1473798
X1470649
X1464351
X1461202
X1458052
X1454902
X1451753
X1448603
X1486397Y283052
X1483247
X1480098
X1476949Y283051
X1473798Y283052
X1470649
X1464351
X1461202
X1458051Y283051
X1454902Y283052
X1451754Y283053
X1448603
X1489546Y279902
X1483247
X1476948
X1473798
X1470649
X1464351
X1461202
X1458052
X1454902
X1451753
X1448603
X1445454
X1442304
X1483247Y276753
X1480098
X1476948
X1473798
X1470649
X1464351
X1461202
X1458052
X1454902
X1451753
X1448603
X1445454
X1464424Y273676
X1486397Y273603
X1483247
X1480098
X1476948
X1473798
X1470649
X1461202
X1458052
X1454902
X1451753
X1448603
X1445454
X1442304
X1489546Y270454
X1486397
X1483247
X1480098
X1476948
X1473798
X1470649
X1454902
X1451753
X1448603
X1445454
X1442303
X1461300Y270400
X1458102Y270402
X1496030Y267665
X1483247Y267304
X1480098
X1451753
X1448603
X1445454
X1442303Y267303
X1486574Y267127
X1469829Y266909
X1461400Y264700
X1608731Y180819
X1616286Y176515
X1613650Y173750
X1609222Y173389
X1611500Y172900
X1615900Y172800
X1601142Y172185
X1597642Y172184
X1595042
X1600490Y167459
X1616891Y165885
X1613741
X1610591
X1616890Y162735
X1613741
X1610591
X1607441
X1616890Y159585
X1613741
X1610591
X1607442
X1591950Y158250
X1600490Y158010
X1596427Y157975
X1588176Y157600
X1613741Y156436
X1610591
X1607441
X1604169Y156407
X1613741Y153286
X1610591
X1607441
X1616900Y153200
X1590569Y152464
X1595390Y151778
X1600148Y151711
X1616891Y150137
X1613741
X1610591
X1604292
X1594565Y148720
X1600182Y148562
X1616891Y146987
X1613741
X1610591
X1607401Y146947
X1616900Y143880
X1610645Y143783
X1607441Y143837
X1600148Y142262
X1616893Y140782
X1613741Y140688
X1610591
X1613741Y137538
X1610591
X1607441
X1604292
X1616891Y134389
X1613741
X1610591
X1607441
X1604292Y134388
X1600900Y131900
X1607239Y131358
X1616891Y128089
X1613741
X1610591
X1613690Y124990
X1616891Y124939
X1610591
X1607441
X1613741Y121790
X1610591
X1607441
X1616890Y118641
X1613741Y118640
X1610591
X1607441
X1613741Y115491
X1610591
X1607441
X1616848Y115449
X1616890Y112341
X1610591
X1607441
X1600490Y110766
X1598190Y110711
X1596220Y109470
X1613741Y109191
X1610793Y109190
X1613741Y106042
X1607441
X1602717Y102240
X1608000Y99400
X1604000Y93925
X1606470Y93759
X1658154Y99400
X1653111Y102240
X1671000Y103000
X1620040Y106042
X1629400Y106131
X1632574Y106107
X1626339Y109191
X1632615Y109215
X1638938Y109192
X1645237Y109191
X1648387
X1651536
X1654686
X1657835
X1660985
X1629487Y109280
X1626300Y112300
X1629489Y112341
X1632638
X1638902Y112305
X1641770Y112340
X1645237Y112341
X1648387
X1651536
X1654685
X1657835
X1660985
X1664135
X1667238Y112387
X1626339Y115491
X1629489
X1632638
X1642084Y115494
X1645237Y115491
X1648387
X1651536
X1657835
X1660985
X1664135
X1667284
X1670434
X1678127Y117293
X1623189Y118640
X1629489
X1632639
X1635788
X1638938Y118641
X1645237Y118640
X1654673Y118628
X1657835Y118640
X1660985
X1664135
X1626339Y118651
X1642150Y118660
X1676886Y120038
X1626364Y121765
X1651536Y121790
X1657835
X1660985
X1664135
X1667284
X1676886Y123188
X1673883Y124308
X1623190Y124940
X1626339
X1632639
X1642087
X1645237
X1651536Y124939
X1654686Y124940
X1657835
X1660985Y124939
X1638250Y125750
X1620040Y128089
X1623190
X1651536
X1660985
X1664135
X1667284
X1635750Y128240
X1645378Y128378
X1677386Y129638
X1629489Y131239
X1635788
X1638937
X1651536
X1654685
X1660985
X1667284
X1677386Y132788
X1674685Y134217
X1620040Y134388
X1623190
X1651536
X1654686Y134389
X1657835
X1629489Y137538
X1635788
X1638937
X1651532Y137534
X1654678Y137530
X1657836Y137538
X1660986
X1664136
X1667284Y137537
X1620040Y140687
X1623190
X1651536
X1654685
X1657836Y140688
X1660985
X1664134
X1629489Y143837
X1635788
X1638937
X1642087
X1651536
X1654685
X1657835
X1660985
X1620040Y146987
X1623190
X1651536Y146988
X1654685Y146987
X1657835
X1660985
X1664186Y147038
X1637363Y149484
X1626339Y150136
X1629489
X1654686Y150138
X1657835Y150136
X1660985Y150137
X1667284Y150136
X1620100Y150200
X1648430Y150163
X1623200Y153100
X1620100Y153300
X1626313Y153312
X1629489Y153286
X1632638
X1635788
X1638938
X1642087
X1648393Y153280
X1654686Y153288
X1657836
X1664135Y153286
X1648386Y156435
X1651536
X1654686Y156436
X1660985Y156435
X1664134Y156436
X1667348Y156500
X1620040Y159585
X1623189
X1626339
X1629489
X1635788
X1638938
X1642087
X1645237
X1648387
X1651536
X1657835
X1660985
X1654638Y159685
X1623250Y162611
X1645151Y162649
X1620040Y162735
X1626339
X1629489
X1635788
X1638938
X1642101Y162749
X1648326Y162674
X1651536Y162735
X1654685
X1657835
X1660985
X1623276Y165798
X1620041Y165885
X1626339Y165884
X1629489
X1635788Y165885
X1638938Y165884
X1642088Y165885
X1645237Y165884
X1648386Y165885
X1651536Y165884
X1657835
X1660985Y165885
X1620006Y168956
X1643662Y172609
X1665063Y172608
X1668213
X1648320Y172690
X1624966Y172936
X1627998Y172854
X1621942Y173237
X1622217Y177809
X1688207Y168972
X1689785Y161180
X1735989Y149050
X1717014Y148950
X1714114
X1739064Y145800
X1726464
X1723264Y145850
X1720164Y145800
X1734989Y142750
X1739064Y142650
X1723314
X1717014
X1693586Y142438
X1681586Y141438
X1691207Y139891
X1739064Y139500
X1735914
X1731789Y139450
X1726539
X1723314Y139500
X1720164
X1717014
X1695236Y138938
X1739064Y136350
X1728789Y136250
X1695236Y135788
X1731903Y133712
X1735989Y133250
X1726464Y133200
X1723314
X1720164
X1717014
X1693625Y133220
X1739064Y130050
X1723314
X1680402Y128652
X1709000Y127200
X1739064Y126900
X1723314
X1720164Y126800
X1739064Y123750
X1735912
X1729444Y123782
X1726464Y123750
X1723314
X1720164
X1739064Y120600
X1726464
X1723314Y120601
X1720164Y120600
Y117451
X1739064Y117450
X1735914
X1726464
X1723314
X1739064Y114300
X1726464Y111150
X1723314
X1720164
X1717014
X1739064Y108000
X1735914
X1723314
X1720164
X1717014
X1735914Y104850
X1723314
X1720164
X1717014
X1726294Y101785
X1735914Y101700
X1723314
Y98550
X1720164Y97550
X1717014
X1743500Y96400
X1742214Y98550
X1745364
X1742214Y101700
X1745500Y104500
X1745363Y108004
X1742214Y111150
X1745768Y111743
X1742214Y114300
X1745364
Y117450
X1742212Y117451
X1742214Y120600
X1745364
X1742214Y123750
X1745364
X1757689Y123850
X1754189Y124250
X1742214Y126900
Y130050
X1746189Y131624
X1752389Y132250
X1746189Y134777
X1752189Y136750
X1751800Y141700
X1742214Y142650
X1745364
X1742214Y145800
X1745364
X1752889Y146250
X1755089Y150750
X1746189Y153250
T03
X25838Y-20458
X38227Y-20485
X50586Y-20687
X59281Y-20641
X67564Y-20745
X409522Y-20794
X422892Y-20789
X436392Y-20760
X656807Y-20652
X1893081Y-20735
X1916078Y-16368
X1906438Y-15968
X1903160Y-19416
X1900256Y-14760
Y-18911
X1893094Y-10142
Y-12642
X1837800Y-3600
X1836700Y-18900
X1835500Y-1700
X1832449Y-8950
X1831000Y-16300
X1828874Y-13520
X1804800Y-1500
X1761872Y-7220
X1680033Y-16711
X1676819Y-16779
X1673500Y-16850
X1617500Y-14500
X1610004Y-17346
X1608500Y-3600
X1607504Y-17346
X1605500Y-3600
X1605004Y-17346
X1602504
X1601102Y-600
X1600004Y-17346
X1598602Y-600
X1597504Y-17346
X1595004
X1590431Y-6702
X1589500Y-600
X1586500Y-16100
X1584447Y-6702
X1584000Y-16100
X1581947Y-6702
X1580398Y-600
X1579447Y-6702
X1571500Y-1406
X1549600Y-10800
X1544882Y-6900
X1522600Y-6500
X1506300Y-6600
X1501900Y-9124
X1498800Y-12676
X1496660Y-10252
X1388294Y-5675
X1385608Y-17485
X1382151Y-5545
X1380678Y-422
X1380008Y-3805
X1379025Y-9799
X1376719Y-16802
X1374100Y-16900
X1371653Y-16654
X1371650Y-907
X1371589Y-3424
Y-5924
X1371632Y-9191
X1371598Y-11633
X1371605Y-14069
X1357489Y-1924
Y-6124
Y-10524
Y-14424
X1357400Y-19800
X1355989Y-3924
X1355950Y-16507
X1355889Y-8524
X1355847Y-12275
X1353154Y-18411
X1350654
X1348154Y-15911
Y-18411
X1345518Y-18476
X1328800Y-12700
X1327600Y-14800
X1326400Y-16900
X1326000Y-12700
X1324800Y-14800
X1323600Y-12600
Y-16900
X1322000Y-14800
X1320800Y-16900
X1319200Y-14800
X1317900Y-16900
X1316300Y-14800
X1315004Y-16933
X1313500Y-14700
X1312300Y-16800
X1310700Y-14700
X1309500Y-16800
X1307900Y-14700
X1306700Y-16800
X1303774Y-18842
X1299549Y-18619
X1299369Y-15680
X1293816Y-13533
X1293600Y-17000
X1287700Y-16700
X1284859Y-14524
X1282252Y-14747
X1278900Y-14800
X1276346Y-10250
X1269800Y-5822
X1265157Y-1743
Y-9901
X1261811Y-1743
Y-9901
X1258464Y-1743
Y-9901
X1255118Y-1743
Y-9901
X1251771Y-1743
Y-9901
X1248425Y-1751
Y-9901
X1245078Y-3700
Y-7851
X1241732Y-1751
Y-9901
X1238385Y-3700
Y-7851
X1235039Y-1751
Y-9901
X1229922Y-2000
X1229874Y-4651
Y-7260
X1229887Y-9864
X1224774Y-1801
Y-4401
X1224800Y-7050
X1224822Y-9700
X1220953Y-4100
Y-7700
X1218307Y-1751
Y-9901
X1214574Y-4100
Y-7851
X1211614Y-1801
Y-9901
X1208267Y-3700
Y-7851
X1204921Y-1751
Y-9901
X1201574Y-3700
Y-7851
X1198228Y-1751
Y-9901
X1193111Y-2000
X1193063Y-4651
Y-7260
X1193076Y-9864
X1187963Y-1801
Y-4401
X1187989Y-7050
X1188011Y-9700
X1184142Y-4100
Y-7700
X1181496Y-1751
Y-9901
X1177763Y-4100
Y-7851
X1174803Y-1801
Y-9901
X1171456Y-3700
Y-7851
X1168110Y-1751
Y-9901
X1164763Y-3700
Y-7851
X1161417Y-1751
Y-9901
X1156300Y-2000
X1156252Y-4651
Y-7260
X1156265Y-9864
X1151152Y-1801
Y-4401
X1151178Y-7050
X1151200Y-9700
X1147331Y-4100
Y-7700
X1144685Y-1751
Y-9901
X1140952Y-4100
Y-7851
X1137992Y-1801
Y-9901
X1134645Y-3700
Y-7851
X1131299Y-1751
Y-9901
X1127952Y-3700
Y-7851
X1124606Y-1751
Y-9901
X1119453Y-9864
X1119440Y-4651
Y-7260
X1114366Y-7050
X1114340Y-1801
Y-4401
X1110520Y-4100
Y-7700
X1107874Y-1751
Y-9901
X1104141Y-4100
Y-7851
X1101181Y-1801
Y-9901
X1097352Y-7180
X1094488Y-4536
Y-9786
X1091141Y-1843
X1087795Y-4536
Y-9786
X1084448Y-1743
Y-7108
X1081102Y-4536
Y-9901
X1077755Y-1743
Y-7108
X1074409Y-4536
Y-9786
X1071062Y-1817
Y-7108
X1067716Y-4536
Y-9901
X1064369Y-1743
Y-7108
X1061023Y-4536
Y-9786
X1057676Y-1743
Y-7108
X1054330Y-4536
Y-9901
X1050983Y-1743
Y-7108
X1047637Y-4536
Y-9901
X1044291Y-2200
X1043800Y-9700
X1030407Y-8938
X1028639Y-6615
X1027202Y-11005
X1020866Y-1858
X1017519
Y-9786
X1014173Y-1858
Y-9786
X1010826Y-1858
Y-9786
X1007480Y-1858
Y-9786
X1004133Y-1742
X1004134Y-7108
X1000787Y-4536
Y-9901
X997441Y-1743
Y-7108
X994094Y-4536
Y-9786
X990748Y-1743
Y-7108
X987401Y-4536
Y-9901
X984055Y-1743
Y-7108
X980708Y-4536
Y-9786
X977362Y-1743
Y-7108
X974015Y-4536
Y-9901
X970669Y-1743
Y-7108
X967322Y-4536
Y-9786
X963976Y-1843
Y-7108
X960629Y-4536
Y-9786
X957765Y-7180
X957283Y-1843
X953936Y-3700
Y-7851
X950590Y-1751
Y-9901
X947243Y-3700
Y-7851
X943897Y-1751
Y-9901
X938758Y-2050
X938732Y-4651
Y-7260
X938745Y-9864
X933658Y-7050
Y-9650
X933632Y-1801
Y-4401
X929811Y-4100
Y-7700
X927165Y-1751
Y-9901
X923432Y-4100
Y-7851
X920472Y-1801
Y-9901
X917125Y-3700
Y-7851
X913779Y-1751
Y-9901
X910432Y-3700
Y-7851
X907086Y-1751
Y-9901
X901947Y-2050
X901921Y-4651
Y-7260
X901934Y-9864
X896821Y-1801
Y-4401
X896847Y-7050
Y-9650
X893000Y-4100
Y-7700
X890354Y-1751
Y-9901
X886621Y-4100
Y-7851
X883661Y-1801
Y-9901
X880314Y-3700
Y-7851
X876968Y-1751
Y-9901
X873621Y-3700
Y-7851
X870275Y-1751
Y-9901
X865136Y-2050
X865110Y-4651
Y-7260
X865123Y-9864
X860010Y-1801
Y-4401
X860036Y-7050
Y-9650
X856189Y-4100
Y-7700
X853543Y-1751
Y-9901
X849810Y-4100
Y-7851
X846850Y-1801
Y-9901
X843503Y-3700
Y-7851
X840157Y-1751
Y-9901
X836810Y-3700
Y-7851
X833464Y-1751
Y-9901
X828325Y-2050
X828299Y-4651
Y-7260
X828312Y-9864
X823199Y-1801
Y-4401
X823225Y-7050
Y-9650
X819378Y-4100
Y-7700
X816732Y-1751
Y-9901
X812999Y-4100
Y-7851
X810039Y-1801
Y-9901
X806692Y-3700
Y-7851
X803346Y-1751
Y-9901
X799999Y-3700
Y-7851
X796653Y-1751
Y-9901
X791514Y-2050
X791488Y-4651
Y-7260
X791501Y-9864
X786388Y-1801
Y-4401
X786414Y-7050
Y-9650
X782567Y-4100
Y-7700
X779921Y-1751
Y-9901
X776188Y-4100
Y-7851
X773228Y-1801
Y-9901
X769881
X766300Y-1800
X765400Y-9800
X756176Y-4300
X753600
X735020Y-8858
X734916Y-1587
X734500Y-5700
X732316Y-1587
X732191Y-4087
X731210Y-15134
X728837Y-12763
X728716Y-15465
X726327Y-14658
X723827
X718975Y-4451
X718555Y-16147
X716921Y-6048
X716858Y-14448
X714300Y-1900
X713824Y-18333
X712796Y-16011
X710327Y-11968
X710263Y-14500
X710107Y-19839
X708330Y-17806
X662700Y-17900
X660676Y-2600
X660000Y-17500
X659747Y-12132
X657250Y-2050
X647400Y-6900
X647317Y-1310
X647000Y-9500
Y-12100
X624770Y-640
X623000Y-3000
X620192Y-5822
X615549Y-1743
Y-9901
X612203Y-1743
Y-9901
X608856Y-1743
Y-9901
X605510Y-1743
Y-9901
X602163Y-1743
Y-9901
X598817Y-1751
Y-9901
X595470Y-3700
Y-7851
X592124Y-1751
Y-9901
X588777Y-3700
Y-7851
X585431Y-1751
Y-9901
X580314Y-2000
X580266Y-4651
Y-7260
X580279Y-9864
X575166Y-1801
Y-4401
X575192Y-7050
X575214Y-9700
X571345Y-4100
Y-7700
X568699Y-1751
Y-9901
X564966Y-4100
Y-7851
X562006Y-1801
Y-9901
X558659Y-3700
Y-7851
X555313Y-1751
Y-9901
X551966Y-3700
Y-7851
X548620Y-1751
Y-9901
X543503Y-2000
X543455Y-4651
Y-7260
X543468Y-9864
X538355Y-1801
Y-4401
X538381Y-7050
X538403Y-9700
X534534Y-4100
Y-7700
X531888Y-1751
Y-9901
X528155Y-4100
Y-7851
X525195Y-1801
Y-9901
X521848Y-3700
Y-7851
X518502Y-1751
Y-9901
X515155Y-3700
Y-7851
X511809Y-1751
Y-9901
X506692Y-2000
X506657Y-9864
X506644Y-4651
Y-7260
X501570Y-7050
X501592Y-9700
X501544Y-1801
Y-4401
X497723Y-4100
Y-7700
X495077Y-1751
Y-9901
X491344Y-4100
Y-7851
X488384Y-1801
Y-9901
X485037Y-3700
Y-7851
X481691Y-1751
Y-9901
X478344Y-3700
Y-7851
X474998Y-1751
Y-9901
X469832Y-2051
Y-4651
Y-7260
X469845Y-9864
X464758Y-7050
Y-9652
X464732Y-1801
Y-4401
X460912Y-4100
Y-7700
X458266Y-1751
Y-9901
X454533Y-4100
Y-7851
X451573Y-1801
Y-9901
X447744Y-7180
X444880Y-4536
Y-9786
X441533Y-1843
X438187Y-4536
Y-9786
X434840Y-1743
Y-7108
X431494Y-4536
Y-9901
X428147Y-1743
Y-7108
X424801Y-4536
Y-9786
X421454Y-1817
Y-7108
X418108Y-4536
Y-9701
X414761Y-1743
Y-7108
X411415Y-4536
Y-9786
X408068Y-1743
Y-7108
X404722Y-4536
Y-9901
X401375Y-1743
Y-7108
X398029Y-4536
Y-9901
X394683Y-2200
X394192Y-9700
X380200Y-1200
X380232Y-10900
X377592Y-10880
X376700Y-1300
X374401Y-11346
X371258Y-1858
Y-9800
X367911Y-1858
Y-9786
X364565Y-1858
Y-9786
X361218Y-1858
Y-9786
X357872Y-1858
Y-9786
X354525Y-1742
X354526Y-7108
X351179Y-4536
Y-9901
X347833Y-1743
Y-7108
X344486Y-4536
Y-9786
X341140Y-1743
Y-7108
X337793Y-4536
Y-9901
X334447Y-1743
Y-7108
X331100Y-4536
Y-9786
X327754Y-1743
Y-7108
X324407Y-4536
Y-9901
X321061Y-1743
Y-7108
X317714Y-4536
Y-9786
X314368Y-1843
Y-7108
X311021Y-4536
Y-9786
X308157Y-7180
X307675Y-1843
X304328Y-3700
Y-7851
X300982Y-1751
Y-9901
X297635Y-3700
Y-7851
X294289Y-1751
Y-9901
X289150Y-2050
X289124Y-4651
Y-7260
X289137Y-9864
X284024Y-1801
Y-4401
X284050Y-7050
Y-9650
X280203Y-4100
Y-7700
X277557Y-1751
Y-9901
X273824Y-4100
Y-7851
X270864Y-1801
Y-9901
X267517Y-3700
Y-7851
X264171Y-1751
Y-9901
X260824Y-3700
Y-7851
X257478Y-1751
Y-9901
X252339Y-2050
X252313Y-4651
Y-7260
X252326Y-9864
X247213Y-1801
Y-4401
X247239Y-7050
Y-9650
X243392Y-4100
Y-7700
X240746Y-1751
Y-9901
X237013Y-4100
Y-7851
X234053Y-1801
Y-9901
X230706Y-3700
Y-7851
X227360Y-1751
Y-9901
X224013Y-3700
Y-7851
X220667Y-1751
Y-9901
X215528Y-2050
X215502Y-4651
Y-7260
X215515Y-9864
X210402Y-1801
Y-4401
X210428Y-7050
Y-9650
X206581Y-4100
Y-7700
X203935Y-1751
Y-9901
X200202Y-4100
Y-7851
X197242Y-1801
Y-9901
X193895Y-3700
Y-7851
X190549Y-1751
Y-9901
X187202Y-3700
Y-7851
X183856Y-1751
Y-9901
X178717Y-2050
X178691Y-4651
Y-7260
X178704Y-9864
X173591Y-1801
Y-4401
X173617Y-7050
Y-9650
X169770Y-4100
Y-7700
X167124Y-1751
Y-9901
X163391Y-4100
Y-7851
X160431Y-1801
Y-9901
X157084Y-3700
Y-7851
X153738Y-1751
Y-9901
X150391Y-3700
Y-7851
X147045Y-1751
Y-9901
X141906Y-2050
X141880Y-4651
Y-7260
X141893Y-9864
X136780Y-1801
Y-4401
X136806Y-7050
Y-9650
X132959Y-4100
Y-7700
X130313Y-1751
Y-9901
X126580Y-4100
Y-7851
X123620Y-1801
Y-9901
X120273
X116692Y-1800
X116300Y-9460
X104500Y-1850
X99102Y-12010
X93500Y-18000
X88777Y-10586
X87091Y-16391
X84202Y-11395
X82300Y-16600
X81702Y-11395
X79500Y-16600
X79202Y-11395
X76165Y-1415
X74386Y-18439
X73574Y-1437
X71172Y-18486
X71074Y-1437
X68574
X66061Y-13689
X65164Y-19456
X63683Y-12866
X62536Y-2379
X62486Y-19184
X61152Y-12752
X55713Y-5095
X54307Y-8051
X53382Y-1173
X52744Y-4368
X52389Y-14258
X45429Y-4669
X42520Y-16896
X41677Y-14390
X40994Y-7148
X30600Y-12000
X25827Y-16958
X22499Y-19381
X19924Y-18875
X16550Y18300
X19964Y18793
X23728Y18731
X25060Y16214
X33370Y5185
X33628Y131
X34719Y19455
X37739Y19501
X39530Y5205
X45700Y40
X45670Y5185
X51090Y8080
X59061Y476
X60035Y7508
X61446Y18238
X61994Y362
X62008Y13249
X62076Y5575
X64159Y11303
X64200Y17389
X65800Y14200
X68611Y1158
X71111
X73611
X76247Y1189
X79096Y9886
X79116Y12361
X79372Y14895
X81610Y9159
X81669Y11693
X82013Y14129
X105892Y8700
X106000Y17260
X114000Y3500
X114100Y6120
X114680Y17320
X120273Y9157
Y16839
X123620Y9114
Y17157
X126616Y14714
X126666Y12114
X130163Y9114
X130313Y17157
X132959Y12114
Y14814
X136780Y9098
Y11700
Y14300
X136756Y16900
X141856Y9100
X141880Y11914
Y14514
Y17114
X147045Y9114
Y17157
X150391Y12114
Y14814
X153738Y9114
Y17157
X157084Y12114
Y14814
X160431Y9114
Y17157
X163427Y14714
X163477Y12114
X166974Y9114
X167124Y17157
X169770Y12114
Y14814
X173591Y9098
Y11700
Y14300
X173567Y16900
X178667Y9100
X178691Y11914
Y14514
Y17114
X183856Y9114
Y17157
X187202Y12114
Y14814
X190549Y9114
Y17157
X193895Y12114
Y14814
X197242Y9114
Y17157
X200238Y14714
X200288Y12114
X203785Y9114
X203935Y17157
X206581Y12114
Y14814
X210402Y9098
Y11700
Y14300
X210378Y16900
X215478Y9100
X215502Y11914
Y14514
Y17114
X220667Y9114
Y17157
X224013Y12114
Y14814
X227360Y9114
Y17157
X230706Y12114
Y14814
X234053Y9114
Y17157
X237049Y14714
X237099Y12114
X240596Y9114
X240746Y17157
X243392Y12114
Y14814
X247213Y9098
Y11700
Y14300
X247189Y16900
X252289Y9100
X252313Y11914
Y14514
Y17114
X257478Y9114
Y17157
X260824Y12114
Y14814
X264171Y9114
Y17157
X267517Y12114
Y14814
X270864Y9114
Y17157
X273910Y12114
X273860Y14714
X277407Y9114
X277557Y17157
X280203Y12114
Y14814
X284024Y9098
Y11700
Y14300
X284000Y16900
X289100Y9100
X289124Y11914
Y14514
Y17114
X294289Y9114
Y17157
X297635Y12114
Y14814
X300982Y9114
Y17157
X304328Y12114
Y14814
X307675Y9300
X307992Y13200
X311021Y17057
X314368Y9114
X317714Y17057
X321061Y9114
X321192Y13200
X327754Y17057
X331100Y9114
X334292Y13200
X337793Y17057
X341140Y9122
X347833Y17057
X351179Y9122
X357492Y11714
Y14314
X357672Y9114
X357872Y17014
X361218Y9114
X362662Y17014
X364565Y9114
X365311Y17042
X367911Y9114
Y17042
X373670Y17580
X374773Y19819
X375792Y6500
X378792
X394682Y11792
Y17157
X398029Y9107
X401376Y17042
X408069Y9107
X408184Y13200
X411416Y17057
X418108Y9107
Y17042
X421368Y13200
X424801Y9107
X428149Y17057
X431494Y9107
X433508Y13200
X434842Y17057
X441533Y9107
Y17042
X448226Y11100
X448292Y13700
X448892Y17000
X451573Y9114
Y17157
X454619Y12114
X454569Y14714
X458116Y9114
X458266Y17157
X460912Y12114
Y14814
X464732Y9098
Y11700
Y14300
X464692Y16900
X469792Y9300
X469832Y11914
Y14514
Y17114
X474998Y9114
Y17157
X478344Y12114
Y14814
X481691Y9114
Y17157
X485037Y12114
Y14814
X488384Y9114
Y17157
X491430Y12114
X491380Y14714
X494927Y9114
X495077Y17157
X497723Y12114
Y14814
X501544Y9098
Y11700
Y14300
X501504Y16900
X506604Y9300
X506644Y11914
Y14514
Y17114
X511809Y9114
Y17157
X515155Y12114
Y14814
X518502Y9114
Y17157
X521848Y12114
Y14814
X525195Y9114
Y17157
X528241Y12114
X528191Y14714
X531738Y9114
X531888Y17157
X534534Y12114
Y14814
X538315Y16900
X538355Y9098
Y11700
Y14300
X543415Y9300
X543455Y11914
Y14514
Y17114
X548620Y9114
Y17157
X551966Y12114
Y14814
X555313Y9114
Y17157
X558659Y12114
Y14814
X561868Y17019
X562006Y9114
X564992Y14714
X565052Y12114
X568549Y9114
X568699Y17157
X571345Y12114
Y14814
X575166Y9098
Y11700
Y14300
X575182Y16900
X580192Y9300
X580266Y11914
Y14514
Y17114
X585431Y9114
Y17157
X588777Y12114
Y14814
X592124Y9114
Y17157
X595470Y12114
Y14814
X598817Y9157
Y17057
X602163Y9157
Y16999
X605510Y9157
Y16999
X608856Y9157
Y16999
X612203Y9157
Y16999
X615549Y9157
Y16999
X620092Y13078
X648550Y8550
X648500Y11600
X651100Y8650
Y11700
X651300Y17500
X663300Y10000
X663699Y3861
X665942Y4716
X666100Y10000
X669300Y9847
X671800
X674300
X679936Y18406
X680200Y13100
X690000Y15300
X692500
X698470Y19669
X701100Y8100
X701120Y19619
X704150Y19650
X704450Y4950
X705250Y8600
X710800Y7100
X714337Y2852
Y5352
Y7852
X719400Y14300
X724837Y13852
X729600Y17991
X731457Y8471
X732335Y6000
X732600Y3600
X734256Y17991
X751900Y400
X754600Y300
X755000Y17255
X755500Y8700
X760100Y17255
X764100Y17100
X769881Y9157
Y16839
X773228Y9114
Y17157
X776224Y14714
X776274Y12114
X779771Y9114
X779921Y17157
X782567Y12114
Y14814
X786388Y9098
Y11700
Y14300
X786364Y16900
X791464Y9100
X791488Y11914
Y14514
Y17114
X796653Y9114
Y17157
X799999Y12114
Y14814
X803346Y9114
Y17157
X806692Y12114
Y14814
X810039Y9114
Y17157
X813035Y14714
X813085Y12114
X816582Y9114
X816732Y17157
X819378Y12114
Y14814
X823199Y9098
Y11700
Y14300
X823175Y16900
X828275Y9100
X828299Y11914
Y14514
Y17114
X833464Y9114
Y17157
X836810Y12114
Y14814
X840157Y9114
Y17157
X843503Y12114
Y14814
X846850Y9114
Y17157
X849846Y14714
X849896Y12114
X853393Y9114
X853543Y17157
X856189Y12114
Y14814
X860010Y9098
Y11700
Y14300
X859986Y16900
X865086Y9100
X865110Y11914
Y14514
Y17114
X870275Y9114
Y17157
X873621Y12114
Y14814
X876968Y9114
Y17157
X880314Y12114
Y14814
X883661Y9114
Y17157
X886707Y12114
X886657Y14714
X890204Y9114
X890354Y17157
X893000Y12114
Y14814
X896821Y9098
Y11700
Y14300
X896797Y16900
X901897Y9100
X901921Y11914
Y14514
Y17114
X907086Y9114
Y17157
X910432Y12114
Y14814
X913779Y9114
Y17157
X917125Y12114
Y14814
X920472Y9114
Y17157
X923518Y12114
X923468Y14714
X927015Y9114
X927165Y17157
X929811Y12114
Y14814
X933632Y9098
Y11700
Y14300
X933608Y16900
X938708Y9100
X938732Y11914
Y14514
Y17114
X943897Y9114
Y17157
X947243Y12114
Y14814
X950590Y9114
Y17157
X953936Y12114
Y14814
X957283Y9300
X957600Y13200
X960629Y17057
X963976Y9114
X967322Y17057
X970669Y9114
X970800Y13200
X977362Y17057
X980708Y9114
X983900Y13200
X987401Y17057
X990748Y9122
X997441Y17057
X1000787Y9122
X1007100Y11714
Y14314
X1007280Y9114
X1007480Y17014
X1010826Y9114
X1012270Y17014
X1014173Y9114
X1014919Y17042
X1017519Y9114
Y17042
X1023740Y18150
X1025670Y6640
X1026700Y1700
X1028400Y6500
X1044290Y11792
X1045525Y15357
X1047637Y9107
X1050984Y17042
X1057677Y9107
X1057792Y13200
X1061024Y17057
X1067716Y9107
Y17042
X1070976Y13200
X1074409Y9107
X1077757Y17057
X1081102Y9107
X1083116Y13200
X1084450Y17057
X1091141Y9107
Y17042
X1097834Y11100
X1097900Y13700
X1098500Y17000
X1101181Y9114
Y17157
X1104227Y12114
X1104177Y14714
X1107724Y9114
X1107874Y17157
X1110520Y12114
Y14814
X1114340Y9098
Y11700
Y14300
X1114300Y16900
X1119400Y9300
X1119440Y11914
Y14514
Y17114
X1124606Y9114
Y17157
X1127952Y12114
Y14814
X1131299Y9114
Y17157
X1134645Y12114
Y14814
X1137992Y9114
Y17157
X1141038Y12114
X1140988Y14714
X1144535Y9114
X1144685Y17157
X1147331Y12114
Y14814
X1151112Y16900
X1151152Y9098
Y11700
Y14300
X1156212Y9300
X1156252Y11914
Y14514
Y17114
X1161417Y9114
Y17157
X1164763Y12114
Y14814
X1168110Y9114
Y17157
X1171456Y12114
Y14814
X1174803Y9114
Y17157
X1177849Y12114
X1177799Y14714
X1181346Y9114
X1181496Y17157
X1184142Y12114
Y14814
X1187923Y16900
X1187963Y9098
Y11700
Y14300
X1193023Y9300
X1193063Y11914
Y14514
Y17114
X1198228Y9114
Y17157
X1201574Y12114
Y14814
X1204921Y9114
Y17157
X1208267Y12114
Y14814
X1211614Y9114
Y17157
X1214600Y14714
X1214660Y12114
X1218157Y9114
X1218307Y17157
X1220953Y12114
Y14814
X1224774Y9098
Y11700
Y14300
X1224790Y16900
X1229800Y9300
X1229874Y11914
Y14514
Y17114
X1235039Y9114
Y17157
X1238385Y12114
Y14814
X1241732Y9114
Y17157
X1245078Y12114
Y14814
X1248425Y9157
Y17057
X1251771Y9157
Y16999
X1255118Y9157
Y16999
X1258464Y9157
Y16999
X1261000Y9100
X1261811Y16999
X1265157Y9157
Y16999
X1269700Y13078
X1292692Y1008
X1301100Y2700
X1301200Y12610
Y15200
X1301279Y10058
X1302300Y4800
X1303900Y2700
X1304000Y12610
Y15200
X1304079Y10058
X1305100Y4800
X1306700Y2700
X1306800Y12610
Y15200
X1306879Y10058
X1307900Y4800
X1309500Y2700
X1310700Y4800
X1312300Y2700
X1313500Y4800
X1315004Y2567
X1316300Y4700
X1317900Y2600
X1319200Y4700
X1320800Y2600
X1322000Y4700
X1322532Y9822
X1322483Y12834
X1322508Y15734
X1323600Y2600
X1324800Y4700
X1325332Y9822
X1325308Y15734
X1325383Y12634
X1326400Y2600
X1327600Y4700
X1328045Y15831
X1328085Y9865
X1328123Y12730
X1328987Y2525
X1355950Y-7
Y2493
X1356261Y15517
X1357600Y5140
X1357700Y17800
X1359450Y-7
Y2493
X1360400Y10600
X1366789Y5776
X1369389
X1371900Y15400
Y17800
X1374431Y15170
X1375676Y7630
X1376094Y4406
X1376842Y15185
X1380219Y5581
X1380300Y2944
X1389523Y4966
X1400100Y10000
X1400616Y13795
X1402600Y10000
X1405100
X1407422Y13139
X1410600Y9100
X1410571Y13170
X1413721Y13139
X1416871
X1420019Y13466
X1422442Y11563
X1427442
X1429469Y13466
X1431025Y7756
X1432661Y5220
X1436025Y7756
X1436131Y5248
X1438918Y13533
X1441340Y11563
X1446340
X1448367Y13533
X1449991Y5589
X1450508Y2756
X1454715Y2784
X1454991Y5589
X1457814Y13466
X1460237Y11563
X1465237
X1467264Y13533
X1469388Y5589
X1469807Y2967
X1473674Y2953
X1474388Y5589
X1476712Y13466
X1477100Y2400
X1479135Y11563
X1481600Y5300
X1484135Y11563
X1485242Y4589
X1486162Y13500
X1488770Y6909
X1489600Y4000
X1492900
X1493770Y6909
X1495611Y13466
X1506900Y3500
X1509400
X1511900
X1513700Y7082
X1514400Y3500
X1516900
X1520100
X1520700Y7100
X1524800Y3500
X1527600
X1527700Y6963
X1530800Y3500
X1534000
X1538520Y11911
X1540000Y3400
X1541400Y12500
X1543500Y3400
X1544698Y12506
X1546800Y3400
X1548698Y12506
X1549800Y3400
X1551309Y12792
X1552300Y3400
X1554148Y12306
X1554800Y3400
X1558000
X1558148Y12306
X1560500Y3400
X1560700Y13000
X1563200Y3400
X1563498Y12506
X1566000Y3400
X1567498Y12506
X1569000Y3400
X1570200Y12900
X1573048Y12506
X1577048
X1579773Y13257
X1580398Y5400
X1581998Y11355
X1586998
X1589259Y10241
X1591848Y11406
X1592453Y8502
X1595848Y11406
X1597700Y9000
X1598602Y3437
X1600898Y11355
X1605898
X1606700Y4600
X1608123Y13302
X1609833Y5425
X1614833
X1615000Y12000
X1617000Y9500
X1619100Y6500
X1619798Y10755
X1623900Y4600
X1624798Y10755
X1626400Y4600
X1627500Y11700
X1629148Y6825
X1634148
X1634200Y9700
X1636500Y4600
X1638550Y7200
X1638865Y11105
X1643865
X1646200Y5300
X1646400Y13400
X1648748Y6325
X1653100Y11500
X1653748Y6325
X1654800Y13518
X1656600Y6300
X1657369Y10258
X1662373Y10154
X1664200Y5400
X1664823Y13287
X1666500Y10500
X1666979Y6236
X1671979
X1672427Y9700
X1675800Y4100
X1676428Y11381
X1680034Y2863
X1681428Y11381
X1682985Y2901
X1684902Y13472
X1685500Y3000
X1685948Y10725
X1688000Y3000
X1690948Y10725
X1691000Y3000
X1691541Y13226
X1695200Y11317
X1700200
X1702421Y13231
X1704771Y11261
X1709771
X1711863Y13276
X1714297Y11180
X1719297
X1721559Y13500
X1723678Y11381
X1728678
X1730768Y13313
X1734875Y9238
X1741544Y9151
X1744900Y9100
X1749085Y9177
X1752908Y9481
X1755500Y9076
X1759093Y9310
X1785366Y8100
X1785612Y10729
X1788421Y8122
X1790078Y11860
X1795078Y11900
X1798676Y11726
X1799462Y8830
X1804462
X1804508Y11858
X1808603Y9300
X1808795Y12165
X1813795
X1813913Y2287
X1816723Y9781
X1816693Y13331
X1819800Y2100
X1823600Y8800
X1824564Y3441
X1825324Y1000
X1828824Y3699
X1829888Y10735
X1830344Y13397
X1832842Y13500
X1832900Y10300
X1835600Y3900
X1837900Y9700
X1838100Y3900
X1838850Y13160
X1840400Y9700
X1843426Y9528
X1845420Y13310
X1848322Y12723
X1868286Y12848
X1871163Y13186
X1876792Y18461
X1882999Y7383
X1883041Y15814
X1878997Y37546
X1876881Y22181
X1870600Y25000
X1867619Y39779
X1856333Y34518
X1853467Y35000
X1849027Y34426
X1846527Y34435
X1841289Y21631
X1841060Y35540
X1837500Y35700
X1829580Y38620
X1829636Y26680
X1826414Y35486
X1825870Y21587
X1824130Y39703
X1823300Y21700
X1820457Y39128
X1819800Y35500
X1819837Y21700
X1817352Y36909
X1817186Y39929
X1815150Y26650
X1812352Y36949
X1809822Y26585
X1808444Y37152
X1808100Y21800
X1807127Y26918
X1803300Y39900
X1799774Y34890
X1797700Y36804
Y21018
X1792700Y36871
X1791500Y26918
X1790700Y34900
X1789356Y38286
X1786865Y22375
X1782371Y26832
X1779750Y36530
X1768807Y21512
X1767069Y24010
X1763360
X1763100Y21500
X1760693Y20045
X1758100Y37000
X1756992Y20007
X1756895Y34252
Y30452
X1755400Y37700
X1753903Y22116
X1753059Y35300
X1752000Y38865
X1750250Y35925
X1749941Y21163
X1749364Y38971
X1748152Y23197
X1746552Y38900
X1746550Y35925
X1743500Y39300
X1743152Y23197
X1741000Y21200
X1740598Y39486
X1738168Y22312
X1736700Y39600
X1733910Y38233
X1733168Y22312
X1731183Y39465
X1730550Y21160
X1727383Y39465
X1724758Y38600
X1721758Y39880
X1717958
X1715259Y35602
X1712308Y39350
X1708508
X1706500Y37000
X1703073Y39679
X1699273
X1696795Y38260
X1694098Y39462
X1689098
X1687500Y37000
X1684648Y39462
X1679648
X1678000Y37000
X1675198Y39462
X1670198
X1668009Y37000
X1665748Y39462
X1660944Y36761
X1660748Y39462
X1658559Y37890
X1656298Y39462
X1651298
X1651250Y36750
X1649073Y38200
X1646848Y39462
X1641848
X1639623Y38100
X1637482Y21623
X1637398Y39862
X1632398
X1630121Y37609
X1627715Y39934
X1627380Y36652
X1622635Y39900
X1620050Y35550
X1619000Y38500
X1610450Y37300
X1602840Y37382
X1601650Y24160
X1597800Y24300
X1592829Y24460
X1592200Y37700
X1589623Y24528
X1582923Y37216
X1573473
X1564023
X1554573
X1554434Y23856
X1551834
X1549334
X1545572Y38188
X1545111Y24172
X1542179Y39695
X1528384Y28040
X1524154Y28918
X1521900Y27500
X1521092Y21665
X1509500Y31900
X1504400Y20300
X1497711Y34427
X1489311Y34830
X1479863
X1470862Y38209
X1470414Y34830
X1460965
X1451516
X1442067
X1432619
X1423170Y36635
X1413721Y36749
X1388627Y35032
X1381642Y25898
X1380950Y30232
X1379200Y27000
X1377009Y39753
X1372400Y37785
X1371950Y20200
X1371900Y31100
Y28600
Y26100
X1371941Y22617
X1369700Y37800
X1367100
X1359800Y37300
X1359761Y34817
Y32317
X1357900Y30200
X1357800Y26100
X1357803Y22200
X1357300Y37300
X1356376Y24167
X1356261Y34517
Y32017
X1356300Y20100
X1356200Y28200
X1321452Y31803
X1318700Y31943
X1316300Y31911
X1313942Y30714
X1311809Y32096
X1309760Y30691
X1304940Y32350
X1296908Y36900
X1267960Y28494
X1265157Y36057
Y27899
X1261811Y36057
Y27899
X1258464Y36057
Y27899
X1255118Y36057
Y27899
X1251771Y36057
Y27899
X1248425Y36049
Y27899
X1245078Y34100
Y29949
X1241732Y36049
Y27899
X1238385Y34100
Y29949
X1235039Y36049
Y27899
X1229874Y33149
Y30540
X1229887Y27936
X1229800Y35750
X1224774Y35999
Y33399
X1224800Y30750
Y28100
X1220953Y33700
Y30100
X1218307Y36049
Y27899
X1214574Y33700
Y29949
X1211614Y35999
Y27899
X1208267Y34100
Y29949
X1204921Y36049
Y27899
X1201574Y34100
Y29949
X1198228Y36049
Y27899
X1193063Y33149
Y30540
X1193076Y27936
X1193023Y35800
X1187963Y35999
Y33399
X1187989Y30750
X1188023Y28100
X1184142Y33700
Y30100
X1181496Y36049
Y27899
X1177763Y33700
Y29949
X1174803Y35999
Y27899
X1171456Y34100
Y29949
X1168110Y36049
Y27899
X1164763Y34100
Y29949
X1161417Y36049
Y27899
X1156251Y33149
Y30540
X1156265Y27936
X1156211Y35800
X1151152Y35999
X1151151Y33399
X1151177Y30750
X1151211Y28100
X1147331Y33700
Y30100
X1144685Y36049
Y27899
X1140952Y33700
Y29949
X1137992Y35999
Y27899
X1134645Y34100
Y29949
X1131299Y36049
Y27899
X1127952Y34100
Y29949
X1124606Y36049
Y27899
X1119453Y27936
X1119400Y35800
X1119440Y33149
Y30540
X1114366Y30750
X1114400Y28100
X1114340Y35999
Y33399
X1110520Y33700
Y30100
X1107874Y36049
Y27899
X1104141Y33700
Y29949
X1101181Y35999
Y27899
X1098022Y35761
X1097900Y31900
X1097834Y28100
X1091141Y35942
Y28007
X1083116Y32100
X1081102Y35942
Y28007
X1074409Y35942
Y28007
X1070976Y32100
X1067716Y35942
Y28007
X1057792Y32100
X1057677Y35942
Y28007
X1047637Y35942
Y28007
X1030400Y26150
X1030450Y23150
X1025291Y20734
X1017519Y35942
Y28014
X1014173Y35942
Y28014
X1010826Y35942
Y28014
X1008217Y35942
X1008227Y33342
X1008200Y30736
X1007480Y28014
X1000787Y35957
X997441Y28022
X990748Y35957
X987401Y28014
X983900Y32100
X980708Y35957
X977362Y28014
X970942Y32100
X970669Y35957
X967322Y28014
X963976Y35957
X960629Y28014
X957700Y32100
X957283Y35957
X953936Y34100
Y29949
X950590Y36049
Y27899
X947243Y34100
Y29949
X943897Y36049
Y27899
X938758Y35750
X938732Y33149
Y30540
X938745Y27936
X933658Y30750
Y28150
X933632Y35999
Y33399
X929811Y33700
Y30100
X927165Y36049
Y27899
X923432Y33700
Y29949
X920472Y35999
Y27899
X917125Y34100
Y29949
X913779Y36049
Y27899
X910432Y34100
Y29949
X907086Y36049
Y27899
X901947Y35750
X901921Y33149
Y30540
X901934Y27936
X896821Y35999
Y33399
X896847Y30750
Y28150
X893000Y33700
Y30100
X890354Y36049
Y27899
X886621Y33700
Y29949
X883661Y35999
Y27899
X880314Y34100
Y29949
X876968Y36049
Y27899
X873621Y34100
Y29949
X870275Y36049
Y27899
X865136Y35750
X865110Y33149
Y30540
X865123Y27936
X860010Y35999
Y33399
X860036Y30750
Y28150
X856189Y33700
Y30100
X853543Y36049
Y27899
X849810Y33700
Y29949
X846850Y35999
Y27899
X843503Y34100
Y29949
X840157Y36049
Y27899
X836810Y34100
Y29949
X833464Y36049
Y27899
X828325Y35750
X828299Y33149
Y30540
X828312Y27936
X823199Y35999
Y33399
X823225Y30750
Y28150
X819378Y33700
Y30100
X816732Y36049
Y27899
X812999Y33700
Y29949
X810039Y35999
Y27899
X806692Y34100
Y29949
X803346Y36049
Y27899
X799999Y34100
Y29949
X796653Y36049
Y27899
X791514Y35750
X791488Y33149
Y30540
X791501Y27936
X786388Y35999
Y33399
X786414Y30750
Y28150
X782567Y33700
Y30100
X779921Y35983
Y27899
X776188Y33700
Y29949
X773228Y35983
Y27899
X769881
X765900Y35800
X763500Y23940
X756714Y23130
X756100Y36200
X753675Y23239
X736655Y38531
X736715Y33487
X736631Y36122
X734155Y38531
X734201Y33510
X734131Y36122
X729500Y23500
X726250Y23550
X723715Y23462
X717720Y23279
X716900Y38500
X715114Y26395
X714823Y23610
X714023Y38653
X711791Y23716
X711100Y38700
X708000Y26600
X704500Y26300
X701525Y35610
X700904Y38439
X700500Y26600
X692400Y20800
X689900
X689500Y37900
X684904Y39943
X684126Y28137
X683800Y24856
X681426Y28137
X675235Y36797
X673900Y23100
X671400
X670430Y29253
X670400Y26100
X670227Y34277
X668900Y23100
X665396Y23000
X661494Y32946
X659700Y22900
X659200Y31500
X656600
X656300Y22800
X654016Y31150
X653800Y22800
X651442Y31225
X651300Y20000
X648867Y31258
X645430Y31067
X620192Y31978
X615549Y36057
Y27899
X612203Y36057
Y27899
X608856Y36057
Y27899
X605510Y36057
Y27899
X602163Y36057
Y27899
X598817Y36049
Y27899
X595470Y34100
Y29949
X592124Y36049
Y27899
X588777Y34100
Y29949
X585431Y36049
Y27899
X580266Y33149
Y30540
X580279Y27936
X580192Y35750
X575166Y35999
Y33399
X575192Y30750
Y28100
X571345Y33700
Y30100
X568699Y36049
Y27899
X564966Y33700
Y29949
X562006Y35999
Y27899
X558659Y34100
Y29949
X555313Y36049
Y27899
X551966Y34100
Y29949
X548620Y36049
Y27899
X543455Y33149
Y30540
X543468Y27936
X543415Y35800
X538355Y35999
Y33399
X538381Y30750
X538415Y28100
X534534Y33700
Y30100
X531888Y36049
Y27899
X528155Y33700
Y29949
X525195Y35999
Y27899
X521848Y34100
Y29949
X518502Y36049
Y27899
X515155Y34100
Y29949
X511809Y36049
Y27899
X506657Y27936
X506603Y35800
X506643Y33149
Y30540
X501569Y30750
X501603Y28100
X501544Y35999
X501543Y33399
X497723Y33700
Y30100
X495077Y36049
Y27899
X491344Y33700
Y29949
X488384Y35999
Y27899
X485037Y34100
Y29949
X481691Y36049
Y27899
X478344Y34100
Y29949
X474998Y36049
Y27899
X469792Y35800
X469832Y33149
Y30540
X469845Y27936
X464758Y30750
X464792Y28100
X464732Y35999
Y33399
X460912Y33700
Y30100
X458266Y36049
Y27899
X454533Y33700
Y29949
X451573Y35999
Y27899
X448414Y35761
X448292Y31900
X448226Y28100
X441533Y35942
Y28007
X433508Y32100
X431494Y35942
Y28007
X424801Y35942
Y28007
X421368Y32100
X418108Y35942
Y28007
X408184Y32100
X408069Y35942
Y28007
X398029Y35942
Y28007
X380792Y27812
Y24933
X380600Y37400
X367911Y35942
Y28014
X364565Y35942
X361218
X358619Y36031
Y33342
X358592Y30736
X357872Y28014
X351179Y35957
X347833Y28022
X341140Y35957
X337793Y28014
X334292Y32100
X331100Y35957
X327754Y28014
X321334Y32100
X321061Y35957
X317714Y28014
X314368Y35957
X311021Y28014
X308092Y32100
X307675Y35957
X304328Y34100
Y29949
X300982Y36049
Y27899
X297635Y34100
Y29949
X294289Y36049
Y27899
X289150Y35750
X289124Y33149
Y30540
X289137Y27936
X284024Y35999
Y33399
X284050Y30750
Y28150
X280203Y33700
Y30100
X277557Y36049
Y27899
X273824Y33700
Y29949
X270864Y35999
Y27899
X267517Y34100
Y29949
X264171Y36049
Y27899
X260824Y34100
Y29949
X257478Y36049
Y27899
X252339Y35750
X252313Y33149
Y30540
X252326Y27936
X247213Y35999
Y33399
X247239Y30750
Y28150
X243392Y33700
Y30100
X240746Y36049
Y27899
X237013Y33700
Y29949
X234053Y35999
Y27899
X230706Y34100
Y29949
X227360Y36049
Y27899
X224013Y34100
Y29949
X220667Y36049
Y27899
X215528Y35750
X215502Y33149
Y30540
X215515Y27936
X210402Y35999
Y33399
X210428Y30750
Y28150
X206581Y33700
Y30100
X203935Y36049
Y27899
X200202Y33700
Y29949
X197242Y35999
Y27899
X193895Y34100
Y29949
X190549Y36049
Y27899
X187202Y34100
Y29949
X183856Y36049
Y27899
X178717Y35750
X178691Y33149
Y30540
X178704Y27936
X173591Y35999
Y33399
X173617Y30750
Y28150
X169770Y33700
Y30100
X167124Y36049
Y27899
X163391Y33700
Y29949
X160431Y35999
Y27899
X157084Y34100
Y29949
X153738Y36049
Y27899
X150391Y34100
Y29949
X147045Y36049
Y27899
X141906Y35750
X141880Y33149
Y30540
X141893Y27936
X136780Y35999
Y33399
X136806Y30750
Y28150
X132959Y33700
Y30100
X130313Y35983
Y27899
X126580Y33700
Y29949
X123620Y35983
Y27899
X120273
X116070Y35780
X114050Y21320
X106200Y26500
X80000Y29000
Y26000
X77000Y28500
Y25992
X74000Y28500
Y25992
X71000Y28500
Y25992
X68000Y28500
Y25992
X65000Y28500
Y26000
X62000Y28500
Y26000
X59500Y28500
Y26000
X52500Y37700
Y34700
X43960Y20572
X40530Y20220
X27300Y38300
Y34300
X27200Y30600
X27239Y28027
X27102Y25383
X25700Y36200
X25600Y32500
X16400Y24744
X13716Y24861
X11600Y36444
Y33944
X11539Y39927
Y31427
X10600Y25100
X8660Y27274
X3600Y36200
X2934Y26933
X2871Y22791
X1572Y38307
X1068Y24831
X602Y30502
X-3560Y34620
X-10850Y30800
X-20726Y37463
X-20700Y31400
Y28100
Y25200
Y22300
X-20800Y34400
X-20700Y48800
X-20600Y41200
X-20526Y44263
X-20500Y51300
Y54300
Y57300
X-9987Y50899
X-8610Y59810
X-7050Y50900
X-1920Y47290
X-1750Y43320
X-1190Y53240
X1826Y56447
X1863Y59426
X8700Y49700
X8988Y58267
X10925Y56167
X11200Y49600
X11500Y43400
X11539Y47127
X14010Y49570
X14025Y56211
X16625
X22100Y56400
X24064Y59394
X25100Y56300
X25700Y44400
X25900Y40300
X26760Y49595
X27208Y42313
X27239Y47027
X27564Y59394
X27904Y56294
X52500Y40700
Y43700
Y57700
X59000Y43500
Y46500
Y49500
Y56000
Y58500
X61500Y43500
Y46500
Y49500
Y56000
Y58500
X64500Y43500
Y46500
Y49500
X67500Y43500
Y46500
Y49500
X70500Y43500
Y46500
Y49500
X73500Y43500
Y46500
Y49500
X76500Y43500
Y46500
Y49500
X79500Y43500
Y46500
Y49500
X81000Y58500
X105892Y45290
X105898Y55194
X113100Y57770
X114082Y55100
X120273Y46957
Y54839
X123620Y46914
Y54957
X126616Y52514
X126666Y49914
X130163Y46914
X130313Y54957
X132959Y49914
Y52614
X136780Y46898
Y49500
Y52100
X136756Y54700
X141856Y46900
X141880Y49714
Y52314
Y54914
X147045Y46914
Y54957
X150391Y49914
Y52614
X153738Y46914
Y54957
X157084Y49914
Y52614
X160431Y46914
Y54957
X163427Y52514
X163477Y49914
X166974Y46914
X167124Y54957
X169770Y49914
Y52614
X173591Y46898
Y49500
Y52100
X173567Y54700
X178667Y46900
X178691Y49714
Y52314
Y54914
X183856Y46914
Y54957
X187202Y49914
Y52614
X190549Y46914
Y54957
X193895Y49914
Y52614
X197242Y46914
Y54957
X200238Y52514
X200288Y49914
X203785Y46914
X203935Y54957
X206581Y49914
Y52614
X210402Y46898
Y49500
Y52100
X210378Y54700
X215478Y46900
X215502Y49714
Y52314
Y54914
X220667Y46914
Y54957
X224013Y49914
Y52614
X227360Y46914
Y54957
X230706Y49914
Y52614
X234053Y46914
Y54957
X237049Y52514
X237099Y49914
X240596Y46914
X240746Y54957
X243392Y49914
Y52614
X247213Y46898
Y49500
Y52100
X247189Y54700
X252289Y46900
X252313Y49714
Y52314
Y54914
X257478Y46914
Y54957
X260824Y49914
Y52614
X264171Y46914
Y54957
X267517Y49914
Y52614
X270864Y46914
Y54957
X273910Y49914
X277407Y46914
X277557Y54957
X280203Y49914
Y52614
X284024Y46898
Y49500
Y52100
X284000Y54700
X289100Y46900
X289124Y49714
Y52314
Y54914
X294289Y46914
Y54957
X297635Y49914
Y52614
X300982Y46914
Y54957
X304328Y49914
Y52614
X307950Y50729
X311021Y54857
X314368Y46914
X317714Y54857
X321061Y46914
X321192Y51000
X327754Y54857
X331100Y46914
X334292Y51000
X337793Y54857
X341140Y46922
X347833Y54857
X351179Y46922
X357762Y49659
Y52333
X357872Y46914
X358618Y54842
X361218
X364565
X367911Y46914
Y54842
X371042Y46900
X380792Y56500
X394492Y54700
X394682Y49592
X398029Y46907
X401376Y54842
X408069Y46907
X408184Y51000
X411416Y54857
X418108Y46907
Y54842
X421368Y51000
X424801Y46907
X428149Y54857
X431494Y46907
X433508Y51000
X434842Y54857
X441533Y46907
Y54842
X448517Y46975
X448492Y51000
X448973Y54883
X451573Y46900
Y54957
X454619Y49564
X454569Y52514
X458116Y46914
X458266Y54957
X460912Y49914
Y52614
X464732Y46898
Y49500
Y52100
X464692Y54700
X469792Y47100
X469832Y49714
Y52314
Y54914
X474998Y46914
Y54957
X478344Y49914
Y52614
X481691Y46914
Y54957
X485037Y49914
Y52614
X488384Y46914
Y54957
X491430Y49914
X494927Y46914
X495077Y54957
X497723Y49914
Y52614
X501544Y46898
X501543Y49500
Y52100
X501492Y54700
X506592Y47000
X506643Y49714
Y52314
X506644Y54914
X511809Y46914
Y54957
X515155Y49914
Y52614
X518502Y46914
Y54957
X521848Y49914
Y52614
X525195Y46914
Y54957
X528241Y49914
X531738Y46914
X531888Y54957
X534534Y49914
Y52614
X538304Y54700
X538355Y46898
Y49500
Y52100
X543404Y47000
X543455Y49714
Y52314
Y54914
X548620Y46914
Y54957
X551966Y49914
Y52614
X555313Y46914
Y54957
X558659Y49914
Y52614
X562006Y46914
Y54957
X565052Y49914
X565352Y52864
X568549Y46914
X568699Y54957
X571345Y49914
Y52614
X575166Y46898
Y49500
Y52100
X580266Y49714
Y52314
Y54914
X585431Y46914
Y54957
X588777Y49914
Y52614
X592124Y46914
Y54957
X595470Y49914
Y52614
X598817Y46957
Y54857
X602163Y46957
Y54799
X605510Y46957
Y54799
X608856Y46957
Y54799
X612203Y46957
Y54799
X615549Y46957
Y54799
X620070Y50878
X656067Y44639
Y47639
X658567Y44639
Y47639
X663476Y45296
X663500Y48000
X666500
X685000Y46650
X685100Y43000
X692000Y45000
Y48500
X697500Y45000
Y48500
X711100Y41100
X713590Y53260
X713610Y55730
X713620Y58270
X713674Y46822
X714023Y41053
X714000Y43900
X715800Y57000
Y59490
X716176Y46822
X716742Y41062
X716700Y43800
X718600Y46921
X719850Y48970
X721141Y46900
X722312Y48999
X723603Y46929
X731843Y43571
X731887Y40916
X737800Y55800
X751600Y41000
X755500Y46700
Y55200
X763500Y59700
X764100Y55100
X769881Y46957
Y54839
X773228Y46914
Y54957
X776224Y52514
X776274Y49914
X779771Y46914
X779921Y54957
X782567Y49914
Y52614
X786388Y46898
Y49500
Y52100
X786364Y54700
X791464Y46900
X791488Y49714
Y52314
Y54914
X796653Y46914
Y54957
X799999Y49914
Y52614
X803346Y46914
Y54957
X806692Y49914
Y52614
X810039Y46914
Y54957
X813035Y52514
X813085Y49914
X816582Y46914
X816732Y54957
X819378Y49914
Y52614
X823199Y46898
Y49500
Y52100
X823175Y54700
X828275Y46900
X828299Y49714
Y52314
Y54914
X833464Y46914
Y54957
X836810Y49914
Y52614
X840157Y46914
Y54957
X843503Y49914
Y52614
X846850Y46914
Y54957
X849846Y52514
X849896Y49914
X853393Y46914
X853543Y54957
X856189Y49914
Y52614
X860010Y46898
Y49500
Y52100
X859986Y54700
X865086Y46900
X865110Y49714
Y52314
Y54914
X870275Y46914
Y54957
X873621Y49914
Y52614
X876968Y46914
Y54957
X880314Y49914
Y52614
X883661Y46914
Y54957
X886707Y49914
X886657Y52514
X890204Y46914
X890354Y54957
X893000Y49914
Y52614
X896821Y46898
Y49500
Y52100
X896797Y54700
X901897Y46900
X901921Y49714
Y52314
Y54914
X907086Y46914
Y54957
X910432Y49914
Y52614
X913779Y46914
Y54957
X917125Y49914
Y52614
X920472Y46914
Y54957
X923518Y49914
X927015Y46914
X927165Y54957
X929811Y49914
Y52614
X933632Y46898
Y49500
Y52100
X933608Y54700
X938708Y46900
X938732Y49714
Y52314
Y54914
X943897Y46914
Y54957
X947243Y49914
Y52614
X950590Y46914
Y54957
X953936Y49914
Y52614
X957558Y50729
X960629Y54857
X963976Y46914
X967322Y54857
X970669Y46914
X970800Y50860
X977362Y54857
X980708Y46914
X983900Y51000
X987401Y54857
X990748Y46922
X997441Y54857
X1000787Y46922
X1007370Y49659
Y52333
X1007480Y46914
X1008226Y54842
X1010826
X1011126Y46914
X1013873
X1014173Y54842
X1017519Y46914
Y54842
X1020650Y46900
X1030400Y56500
X1031600Y42900
X1044100Y54700
X1044290Y49592
X1047637Y46907
X1050984Y54842
X1057677Y46907
X1057792Y51000
X1061024Y54857
X1067716Y46907
Y54842
X1070976Y51000
X1074409Y46907
X1077757Y54857
X1081102Y46907
X1083116Y51000
X1084450Y54857
X1091141Y46907
Y54842
X1098125Y46975
X1098100Y51000
X1098581Y54883
X1101181Y46900
Y54957
X1104227Y49564
X1104177Y52514
X1107724Y46914
X1107874Y54957
X1110520Y49914
Y52614
X1114340Y46898
Y49500
Y52100
X1114300Y54700
X1119400Y47100
X1119440Y49714
Y52314
Y54914
X1124606Y46914
Y54957
X1127952Y49914
Y52614
X1131299Y46914
Y54957
X1134645Y49914
Y52614
X1137992Y46914
Y54957
X1141038Y49914
X1144535Y46914
X1144685Y54957
X1147331Y49914
Y52614
X1151100Y54700
X1151152Y46898
X1151151Y49500
Y52100
X1156200Y47000
X1156251Y49714
Y52314
X1156252Y54914
X1161417Y46914
Y54957
X1164763Y49914
Y52614
X1168110Y46914
Y54957
X1171456Y49914
Y52614
X1174803Y46914
Y54957
X1177849Y49914
X1181346Y46914
X1181496Y54957
X1184142Y49914
Y52614
X1187912Y54700
X1187963Y46898
Y49500
Y52100
X1193012Y47000
X1193063Y49714
Y52314
Y54914
X1198228Y46914
Y54957
X1201574Y49914
Y52614
X1204921Y46914
Y54957
X1208267Y49914
Y52614
X1211614Y46914
Y54957
X1214660Y49914
X1214960Y52864
X1218157Y46914
X1218307Y54957
X1220953Y49914
Y52614
X1224774Y46898
Y49500
Y52100
X1229874Y49714
Y52314
Y54914
X1235039Y46914
Y54957
X1238385Y49914
Y52614
X1241732Y46914
Y54957
X1245078Y49914
Y52614
X1248425Y46957
Y54857
X1251771Y46957
Y54799
X1255118Y46957
Y54799
X1258464Y46957
Y54799
X1261811Y46957
Y54799
X1265157Y46957
Y54799
X1267959Y47245
X1268022Y54443
X1268111Y58040
X1296928Y48700
X1296935Y51335
X1304500Y40066
X1308100Y41500
X1310600
X1323400Y41439
Y43839
X1324127Y50827
X1326000Y41439
X1326058Y43956
X1327500Y51547
X1327452Y55544
X1341400Y46100
X1343260Y53770
X1348945Y40264
X1351190Y54710
X1351908Y40402
X1356950Y54370
X1362448Y43413
X1362674Y46058
X1363170Y54280
X1365855Y46972
X1369408Y50479
X1370849Y59349
X1371910Y48800
X1376989Y46971
X1379110Y45033
X1380500Y50500
Y54500
X1380900Y59820
X1381817Y46484
X1383171Y57549
X1389138Y58499
X1392050Y55559
Y58559
X1394550Y55559
Y58559
X1397050Y55559
Y58559
X1397500Y51000
X1402700Y51100
X1406546Y43116
X1406674Y46120
X1407150Y52859
Y55859
Y58859
X1410150Y52859
Y55859
Y58859
X1411254Y46018
X1411546Y43116
X1416837Y45477
X1420337
X1425081Y48412
X1630386Y41448
X1658600Y44700
X1667000Y51500
X1669500
X1672000
X1678627Y54616
X1684248Y56746
X1692300Y56900
X1709600Y45800
X1711000Y55525
X1712600Y46100
X1713550Y56000
X1715100Y46100
X1717600
X1720100
X1720500Y52440
X1732650Y58150
X1735150
X1742594Y47106
X1745094
X1746328Y59011
X1748854Y58533
X1750400Y47400
X1766333Y59116
X1771459Y52695
X1775000Y53500
X1788216Y59197
X1799438Y44328
X1802119Y56581
X1808363Y40033
X1815637Y54775
X1818396Y54752
X1826900Y40400
X1834300Y41100
X1838500Y40400
X1848000Y56500
X1848208Y49427
X1850500Y56500
X1850600Y41348
X1855400Y40800
X1858198Y41108
X1860786Y41200
X1868670Y42765
X1875100Y51300
X1878800Y40200
Y43207
X1880986Y53299
X1889218Y43530
Y46030
Y51030
Y53530
Y56030
X1970679Y77969
Y75369
X1968179Y77969
Y75369
X1966212Y72897
X1965679Y77969
Y75369
X1926890Y73106
X1920300Y68300
X1917600Y66000
X1909406Y76790
X1905501Y79790
X1902796Y79820
X1896970Y73460
X1895354Y75650
X1895330Y64390
X1893961Y73365
X1890803Y63189
X1889218Y61030
X1884500Y79300
X1883200Y76600
X1882000Y79300
X1880230Y76820
X1879500Y79300
X1878000Y73950
X1877270Y63473
X1877103Y60791
X1873956Y60299
X1858600Y74300
X1796100Y68800
X1794100Y70898
X1786341Y63341
X1784341Y64841
X1769250Y70350
X1768450Y77376
X1766240Y70500
X1760016Y65774
X1757998Y73637
X1757054Y66059
X1748500Y79500
X1735150Y60650
X1732650
X1725474Y69250
X1720600Y70200
X1715100Y70500
X1707268Y77668
X1702513Y79885
X1700710Y73292
X1697300Y73296
X1696655Y77991
X1694155
X1693900Y73300
X1691655Y77991
X1690500Y73950
X1689155Y77991
X1682396Y74344
X1679900Y74500
X1676428Y74646
X1673800Y75200
X1669350Y69962
X1664350Y72462
Y69962
X1661563Y72028
X1659196Y70291
X1659100Y73614
X1656600
X1653000Y77600
X1650876Y65237
X1649900Y78600
X1648276Y65221
X1640900Y66900
X1637700Y67400
X1635337Y73500
X1632000
X1627489Y74960
X1623200Y75800
X1621100Y69600
X1620733Y74847
X1615115Y70786
X1612000Y70984
X1610853Y63861
X1608500Y72688
X1608452Y62890
X1606797Y64949
X1605184Y61044
X1603138Y65890
X1599500Y75000
X1599000Y61500
X1597987Y79500
X1596050Y75400
X1595943Y71522
X1593000Y78140
X1592715Y70817
X1591600Y75700
X1590464Y77962
X1588962Y75926
X1587734Y70974
X1584748Y70840
X1582407Y75841
X1579807
X1579100Y69000
X1575018Y71213
X1573076Y75328
X1570511Y75396
X1562850Y73642
X1562575Y76231
X1556810Y71760
X1541520Y79387
X1538870Y78980
X1535300Y78490
X1532800Y78590
X1520314Y78880
X1517162Y78784
X1490821Y73750
X1455889Y73700
X1453221Y73750
X1412150Y71259
X1412250Y68359
Y65359
X1410200Y77400
X1409150Y71259
X1409250Y68359
Y65359
X1407964Y79700
X1407300Y77300
X1404964Y79700
X1397550Y68059
X1397539Y65098
X1397400Y78800
Y76200
X1395000Y78800
Y76200
X1395050Y68059
X1394939Y65098
X1392584Y78798
Y76200
X1392339Y65098
X1392149Y68006
X1389068Y78556
X1389100Y74600
X1375500Y76000
X1371500Y63200
X1370975Y67225
X1363500Y77400
X1363040Y66660
X1362900Y60500
X1358500Y74500
X1357000Y60500
X1356760Y66660
X1351488Y74000
X1350800Y66600
X1350830Y60730
X1337400Y72000
X1336900Y61600
X1336850Y76450
X1327467Y70786
X1327500Y68000
Y65300
X1327168Y61483
X1323500Y75000
Y71500
Y68000
X1321841Y63000
X1318341
Y60000
X1308400Y79600
X1304685Y78827
X1304000Y62000
X1301000
X1298422Y74000
X1267976Y73676
X1265157Y73857
Y65699
X1261811Y73857
Y65699
X1258464Y73857
Y65699
X1255118Y73857
Y65699
X1251771Y73857
Y65699
X1248425Y73849
Y65699
X1245078Y71900
Y67749
X1241732Y73849
Y65699
X1238385Y71900
Y67749
X1235039Y73849
Y65699
X1229900Y73550
X1229874Y70949
Y68340
X1229887Y65736
X1224774Y73799
Y71199
X1224800Y68550
Y65950
X1220953Y71500
Y67900
X1218307Y73849
Y65699
X1214574Y71500
Y67749
X1211614Y73799
Y65699
X1208267Y71900
Y67749
X1204921Y73849
Y65699
X1201574Y71900
Y67749
X1198228Y73849
Y65699
X1193089Y73550
X1193063Y70949
Y68340
X1193076Y65736
X1187963Y73799
Y71199
X1187989Y68550
Y65950
X1184142Y71500
Y67900
X1181496Y73849
Y65699
X1177763Y71500
Y67749
X1174803Y73799
Y65699
X1171456Y71900
Y67749
X1168110Y73849
Y65699
X1164763Y71900
Y67749
X1161417Y73849
Y65699
X1156278Y73550
X1156252Y70949
Y68340
X1156265Y65736
X1151152Y73799
Y71199
X1151178Y68550
Y65950
X1147331Y71500
Y67900
X1144685Y73849
Y65699
X1140952Y71500
Y67749
X1137992Y73799
Y65699
X1134645Y71900
Y67749
X1131299Y73849
Y65699
X1127952Y71900
Y67749
X1124606Y73849
Y65699
X1119466Y73550
X1119453Y65736
X1119440Y70949
Y68340
X1114366Y68550
Y65950
X1114340Y73799
Y71199
X1110520Y71500
Y67900
X1107874Y73849
Y65699
X1104141Y71500
Y67749
X1101181Y73799
Y65699
X1098259Y70896
X1098207Y73589
X1098235Y68090
X1091141Y73742
Y65807
X1083116Y69900
X1081102Y73742
Y65807
X1074409Y73742
Y65807
X1070976Y69900
X1067716Y73742
Y65807
X1057792Y69900
X1057677Y73742
Y65807
X1047637Y73742
Y65807
X1044290Y68964
X1030300Y63200
X1023900Y77200
Y74100
X1017350Y73450
X1016600Y65950
X1014350Y73000
X1008099Y73479
X1007480Y65736
X1007380Y70935
Y68335
X1000787Y73757
X997441Y65822
X990748Y73757
X987401Y65814
X983900Y69900
X980708Y73757
X977362Y65814
X970942Y69900
X970669Y73757
X967322Y65814
X963976Y73757
X960629Y65814
X957600Y70400
X957200Y73800
X953936Y71900
Y67749
X950590Y73849
Y65699
X947243Y71900
Y67749
X943897Y73849
Y65699
X938758Y73550
X938732Y70949
Y68340
X938745Y65736
X933658Y68550
Y65950
X933632Y73799
Y71199
X929811Y71500
Y67900
X927165Y65699
X927015Y73849
X923432Y71500
Y67749
X920472Y73799
Y65699
X917125Y71900
Y67749
X913779Y73849
Y65699
X910432Y71900
Y67749
X907086Y73849
Y65699
X901947Y73550
X901921Y70949
Y68340
X901934Y65736
X896821Y73799
Y71199
X896847Y68550
Y65950
X893000Y71500
Y67900
X890354Y73849
Y65699
X886621Y71500
Y67749
X883661Y73799
Y65699
X880314Y71900
Y67749
X876968Y73849
Y65699
X873621Y71900
Y67749
X870275Y73849
Y65699
X865136Y73550
X865110Y70949
Y68340
X865123Y65736
X860010Y73799
Y71199
X860036Y68550
Y65950
X856189Y71500
Y67900
X853543Y73849
Y65699
X849810Y71500
Y67749
X846850Y73799
Y65699
X843503Y71900
Y67749
X840157Y73849
Y65699
X836810Y71900
Y67749
X833464Y73849
Y65699
X828325Y73550
X828299Y70949
Y68340
X828312Y65736
X823199Y73799
Y71199
X823225Y68550
Y65950
X819378Y71500
Y67900
X816732Y65699
X816582Y73849
X812999Y71500
Y67749
X810039Y73799
Y65699
X806692Y71900
Y67749
X803346Y73849
Y65699
X799999Y71900
Y67749
X796653Y73849
Y65699
X791514Y73550
X791488Y70949
Y68340
X791501Y65736
X786388Y73799
Y71199
X786414Y68550
Y65950
X782567Y71500
Y67900
X779921Y73849
Y65699
X776188Y71500
Y67749
X773228Y73799
Y65699
X769881Y66000
X763400Y78300
X751708Y73800
X733671Y75412
X733732Y63747
X733600Y68546
X733642Y66146
X731332Y63801
X731200Y68600
X731242Y66200
X730923Y75315
X724200Y64730
X723700Y67400
X722460Y69550
X715130Y79574
X713680Y60910
X713050Y63650
X710440Y63710
X704880Y66750
X703120Y69380
X702380Y66840
X700640Y69500
X700360Y72160
X699880Y66840
X697747Y72184
X697440Y66900
X697200Y79500
X695000Y67000
X694910Y72220
X678020Y69870
X676610Y77970
X674010
X668100Y68600
X666700Y65600
X665100Y68600
X663700Y65600
X659000Y75300
Y72300
X658100Y69100
Y66100
X656500Y75300
Y72300
X655600Y69100
Y66100
X652500Y75300
Y72300
X650000Y75300
Y72300
X620192Y69778
X615549Y73857
Y65699
X612203Y73857
Y65699
X608856Y73857
Y65699
X605510Y73857
Y65699
X602163Y73857
Y65699
X598817Y73849
Y65699
X595470Y71900
Y67749
X592124Y73849
Y65699
X588777Y71900
Y67749
X585431Y73849
Y65699
X580292Y73550
X580266Y70949
Y68340
X580279Y65736
X575166Y73799
Y71199
X575192Y68550
Y65950
X571345Y71500
Y67900
X568699Y73849
Y65699
X564966Y71500
Y67749
X562006Y73799
Y65699
X558659Y71900
Y67749
X555313Y73849
Y65699
X551966Y71900
Y67749
X548620Y73849
Y65699
X543481Y73550
X543455Y70949
Y68340
X543468Y65736
X538355Y73799
Y71199
X538381Y68550
Y65950
X534534Y71500
Y67900
X531888Y73849
Y65699
X528155Y71500
Y67749
X525195Y73799
Y65699
X521848Y71900
Y67749
X518502Y73849
Y65699
X515155Y71900
Y67749
X511809Y73849
Y65699
X506670Y73550
X506657Y65736
X506644Y70949
Y68340
X501570Y68550
Y65950
X501544Y73799
Y71199
X497723Y71500
Y67900
X495077Y73849
Y65699
X491344Y71500
Y67749
X488384Y73799
Y65699
X485037Y71900
Y67749
X481691Y73849
Y65699
X478344Y71900
Y67749
X474998Y73849
Y65699
X469858Y73550
X469832Y70949
Y68340
X469845Y65736
X464758Y68550
Y65950
X464732Y73799
Y71199
X460912Y71500
Y67900
X458266Y73849
Y65699
X454533Y71500
Y67749
X451573Y73799
Y65699
X448651Y70896
X448599Y73589
X448627Y68090
X441533Y73742
Y65807
X433508Y69900
X431494Y73742
Y65807
X424801Y73742
Y65807
X421368Y69900
X418108Y73742
Y65807
X408184Y69900
X408069Y73742
Y65807
X398029Y73742
Y65807
X394682Y68492
X380980Y60210
X380892Y63200
X374292Y77200
Y74100
X367742Y73450
X366992Y65950
X358491Y73479
X357872Y65736
X357772Y70935
Y68335
X351179Y73757
X347833Y65822
X341140Y73757
X337793Y65814
X334292Y69900
X331100Y73757
X327754Y65814
X321334Y69900
X321061Y73757
X317714Y65814
X314368Y73757
X311021Y65814
X307992Y70400
X307592Y73800
X304328Y71900
Y67749
X300982Y73849
Y65699
X297635Y71900
Y67749
X294289Y73849
Y65699
X289150Y73550
X289124Y70949
Y68340
X289137Y65736
X284024Y73799
Y71199
X284050Y68550
Y65950
X280203Y71500
Y67900
X277557Y65699
X277407Y73849
X273824Y71500
Y67749
X270864Y73799
Y65699
X267517Y71900
Y67749
X264171Y73849
Y65699
X260824Y71900
Y67749
X257478Y73849
Y65699
X252339Y73550
X252313Y70949
Y68340
X252326Y65736
X247213Y73799
Y71199
X247239Y68550
Y65950
X243392Y71500
Y67900
X240746Y73849
Y65699
X237013Y71500
Y67749
X234053Y73799
Y65699
X230706Y71900
Y67749
X227360Y73849
Y65699
X224013Y71900
Y67749
X220667Y73849
Y65699
X215528Y73550
X215502Y70949
Y68340
X215515Y65736
X210402Y73799
Y71199
X210428Y68550
Y65950
X206581Y71500
Y67900
X203935Y73849
Y65699
X200202Y71500
Y67749
X197242Y73799
Y65699
X193895Y71900
Y67749
X190549Y73849
Y65699
X187202Y71900
Y67749
X183856Y73849
Y65699
X178717Y73550
X178691Y70949
Y68340
X178704Y65736
X173591Y73799
Y71199
X173617Y68550
Y65950
X169770Y71500
Y67900
X167124Y65699
X166974Y73849
X163391Y71500
Y67749
X160431Y73799
Y65699
X157084Y71900
Y67749
X153738Y73849
Y65699
X150391Y71900
Y67749
X147045Y73849
Y65699
X141906Y73550
X141880Y70949
Y68340
X141893Y65736
X136780Y73799
Y71199
X136806Y68550
Y65950
X132959Y71500
Y67900
X130313Y73849
Y65699
X126580Y71500
Y67749
X123620Y73799
Y65699
X120273Y66000
X116200Y70387
X115980Y73680
X102100Y73800
X81000Y61500
X79725Y75993
X79500Y79000
Y72500
X78000Y70500
X75500
X73000
X70500
X68000
X65500
X63000Y79000
Y76500
Y74000
Y70500
X61500Y61000
X60500Y79000
Y76500
Y74000
Y70500
X59000Y61000
X52500Y67200
Y63700
Y60700
X30686Y79943
X27625Y73967
X27564Y61894
X27525Y77867
Y69367
X27488Y64671
X26185Y67017
X25925Y75867
X25886Y71467
X24064Y61894
X15111Y62553
X11864Y78494
X11925Y74867
X11864Y71294
X11925Y67811
Y65311
X11864Y62794
X5500Y77444
X3100Y65900
X1382Y68100
X-1470Y63910
X-5930Y79358
X-6010Y61030
X-8370Y62600
X-8562Y79358
X-9390Y67410
X-10470Y64450
X-11452Y79308
X-13610Y64360
X-14102Y79358
X-16602
X-20500Y60300
X-16602Y81858
X-14102
X-11452Y81808
X-8812Y84308
X-8562Y81858
X-5860
X-5912Y84258
X-1000Y81500
X2380Y92670
X3530Y94840
X4880Y92670
X5600Y80444
X6030Y94840
X6500Y84400
X6600Y87900
X7380Y92670
X8530Y94840
X9125Y81267
X9225Y84467
X9425Y88067
X9880Y92670
X11030Y94840
X11625Y81267
X11725Y84467
X11925Y88067
X12380Y92670
X13530Y94840
X14880Y92670
X16030Y94840
X17380Y92670
X18530Y94840
X19880Y92670
X21030Y94840
X22380Y92670
X23530Y94840
X24880Y92670
X25870Y80880
X27800Y83900
Y86900
Y89900
X28294Y80889
X30400Y83800
Y86800
Y89800
X32500Y81791
X34000Y93350
X35650Y91150
X44100Y97800
X46900Y97750
X48700Y90700
Y95500
X51381Y90750
Y95750
X60500Y81500
X60801Y97750
X61300Y89800
X63000Y81500
X63725Y90900
X63858Y97620
X68725Y90900
X71050Y89600
X70980Y97166
X76106Y89337
X79500Y82000
X81861Y93392
X82046Y90043
X86600Y94000
X100140Y83170
X108385Y84291
X109057Y92774
X112007Y93139
X119892Y84700
X120273Y92500
X123620Y84714
Y92757
X126616Y90314
X126666Y87714
X130163Y84714
X130313Y92757
X132959Y87714
Y90414
X136780Y84698
Y87300
Y89900
X136756Y92500
X141856Y84700
X141880Y87514
Y90114
Y92714
X147045Y84714
Y92757
X150391Y87714
Y90414
X153738Y84714
Y92757
X157084Y87714
Y90414
X160431Y84714
Y92757
X163427Y90314
X163477Y87714
X166974Y84714
X167124Y92757
X169770Y87714
Y90364
X173591Y84698
Y87300
Y89900
X173567Y92500
X178667Y84700
X178691Y87514
Y90114
Y92714
X183856Y84714
Y92757
X187202Y87714
Y90414
X190549Y84714
Y92757
X193895Y87714
Y90414
X197242Y84714
Y92757
X200238Y90314
X200288Y87714
X203785Y84714
X203935Y92757
X206581Y87714
Y90414
X210402Y84698
Y87300
Y89900
X210378Y92500
X215478Y84700
X215502Y87514
Y90114
Y92714
X220667Y84714
Y92761
X224013Y87714
Y90414
X227360Y84714
Y92757
X230706Y87714
Y90414
X234053Y84714
Y92757
X237049Y90314
X237099Y87714
X240596Y84714
X240746Y92757
X243392Y87714
Y90414
X247213Y84698
Y87300
Y89900
X247189Y92500
X252289Y84700
X252313Y87514
Y90114
Y92714
X257478Y84714
Y92757
X260824Y87714
Y90414
X264171Y84714
Y92757
X267517Y87714
Y90414
X270864Y84714
Y92757
X273910Y87714
X273860Y90314
X277407Y84714
X277557Y92757
X280203Y87714
Y90414
X284024Y84698
Y87300
Y89900
X284000Y92500
X289100Y84700
X289124Y87514
Y90114
Y92714
X294289Y84714
Y92757
X297635Y87714
Y90414
X300982Y84714
Y92757
X304328Y87714
X304278Y90414
X307675Y92657
X308166Y87394
X311021Y84714
Y89964
X314368Y87392
Y92657
X317714Y84714
Y89964
X321061Y87392
Y92757
X324407Y84599
Y89964
X327754Y87392
Y92757
X331100Y84714
Y89964
X334447Y87392
Y92757
X337793Y84599
Y89964
X341140Y87392
Y92757
X344486Y84714
Y89964
X347833Y87392
Y92757
X351179Y84599
Y89964
X354415Y87392
Y92757
X357872Y87500
X357965Y92500
X362435Y87500
X362792Y92500
X365234Y87500
X365607Y92500
X367911Y87500
X368311Y92500
X375337Y83877
Y86377
X384992Y81600
X386292Y98800
X394682Y87392
X398029Y84800
Y89964
X401375Y87392
Y92757
X404722Y84599
Y89964
X408068Y87392
Y92757
X411415Y84714
Y89964
X414761Y87392
Y92757
X418108Y84599
Y89964
X421454Y92757
X424801Y84800
Y89964
X428147Y87392
Y92500
X431400Y84800
X431494Y89964
X434840Y87392
Y92500
X438187Y84714
Y89964
X441533Y87392
Y92500
X444880Y84714
Y89964
X448610Y85296
X448692Y89900
X451573Y84714
Y92757
X454619Y87714
X454569Y90314
X458116Y84714
X458266Y92757
X460912Y87714
Y90314
X464732Y84698
Y87300
Y89900
X464708Y92500
X469808Y84700
X469832Y87514
Y90114
Y92714
X474998Y84714
Y92757
X478344Y87714
Y90414
X481691Y84714
Y92757
X485037Y87714
Y90414
X488384Y84714
Y92757
X491430Y87714
X491380Y90314
X494927Y84714
X495077Y92757
X497723Y87714
Y90414
X501544Y84698
Y87300
Y89900
X501520Y92500
X506620Y84700
X506644Y87514
Y90114
Y92714
X511809Y84714
Y92757
X515155Y87714
Y90414
X518502Y84714
Y92757
X521848Y87714
Y90414
X525195Y84714
Y92757
X528241Y87714
X528191Y90314
X531738Y84714
X531888Y92757
X534534Y87714
Y90414
X538331Y92500
X538355Y84698
Y87300
Y89900
X543431Y84700
X543455Y87514
Y90114
Y92714
X548620Y84714
Y92757
X551966Y87714
Y90414
X555313Y84714
Y92757
X558659Y87714
Y90414
X562006Y84714
Y92757
X565266Y87374
X568549Y84714
X568699Y92757
X571345Y87714
Y90414
X575142Y92500
X575166Y84698
Y87300
Y89900
X580242Y84700
X580266Y87514
Y90114
Y92714
X585431Y84714
Y92757
X588777Y87714
Y90414
X592124Y84714
Y92757
X595470Y87714
Y90414
X598817Y84757
Y92657
X602163Y84757
Y92599
X605510Y84757
Y92599
X608856Y84757
Y92599
X612203Y84757
Y92599
X615549Y84757
Y92599
X620092Y88678
X626040Y98281
X644904Y92382
X646200Y86300
Y88800
X647304Y91882
X647600Y84200
X649200Y86300
Y88800
X650204Y91282
X652718Y93881
X652804Y90482
X662352Y89566
X664471Y86061
X670795Y89189
X673830Y83050
X673900Y80500
X675630Y94988
X676430Y83050
X676500Y80500
X678300Y92630
Y95130
X681300Y92630
Y95130
X684300Y92630
X687400Y93900
X690100Y93200
X692200Y83800
X693000Y92500
X694600Y85000
X697100Y90600
X698300Y85300
X699800Y89100
X701500Y85500
X703845Y88830
X705972Y86660
X707329Y88955
X709560Y84648
X713115Y88629
X713300Y86000
X713830Y82730
X716268Y88683
X716894Y84047
X720572Y88700
X730038Y88408
X731910Y92790
X732599Y88408
X732734Y82626
X733740Y95230
X735241Y88329
X735700Y82700
X752600Y86200
X752680Y83500
X753100Y92111
X755500Y84361
X756800Y99400
X761650Y94550
X763350Y81220
X763930Y85100
X764000Y95750
X766824Y85943
X769500Y84700
X769881Y92500
X773228Y84714
Y92757
X776224Y90314
X776274Y87714
X779771Y84714
X779921Y92757
X782567Y87714
Y90414
X786388Y84698
Y87300
Y89900
X786364Y92500
X791464Y84700
X791488Y87514
Y90114
Y92714
X796653Y84714
Y92757
X799999Y87714
Y90414
X803346Y84714
Y92757
X806692Y87714
Y90414
X810039Y84714
Y92757
X813035Y90314
X813085Y87714
X816582Y84714
X816732Y92757
X819378Y87714
Y90364
X823199Y84698
Y87300
Y89900
X823175Y92500
X828275Y84700
X828299Y87514
Y90114
Y92714
X833464Y84714
Y92757
X836810Y87714
Y90414
X840157Y84714
Y92757
X843503Y87714
Y90414
X846850Y84714
Y92757
X849846Y90314
X849896Y87714
X853393Y84714
X853543Y92757
X856189Y87714
Y90414
X860010Y84698
Y87300
Y89900
X859986Y92500
X865086Y84700
X865110Y87514
Y90114
Y92714
X870275Y84714
Y92761
X873621Y87714
Y90414
X876968Y84714
Y92757
X880314Y87714
Y90414
X883661Y84714
Y92757
X886707Y87714
X886657Y90314
X890204Y84714
X890354Y92757
X893000Y87714
Y90414
X896821Y84698
Y87300
Y89900
X896797Y92500
X901897Y84700
X901921Y87514
Y90114
Y92714
X907086Y84714
Y92757
X910432Y87714
Y90414
X913779Y84714
Y92757
X917125Y87714
Y90414
X920472Y84714
Y92757
X923518Y87714
X923468Y90314
X927015Y84714
X927165Y92757
X929811Y87714
Y90414
X933632Y84698
Y87300
Y89900
X933608Y92500
X938708Y84700
X938732Y87514
Y90114
Y92714
X943897Y84714
Y92757
X947243Y87714
Y90414
X950590Y84714
Y92757
X953936Y87714
X953886Y90414
X957283Y92657
X957774Y87394
X960629Y84714
Y89964
X963976Y87392
Y92657
X967322Y84714
Y89964
X970669Y87392
Y92757
X974015Y84599
Y89964
X977362Y87392
Y92757
X980708Y84714
Y89964
X984055Y87392
Y92757
X987401Y84599
Y89964
X990748Y87392
Y92757
X994094Y84714
Y89964
X997441Y87392
Y92757
X1000787Y84599
Y89964
X1004023Y87392
Y92757
X1007480Y87500
X1007573Y92500
X1012043Y87500
X1012400Y92500
X1014842Y87500
X1015215Y92500
X1017519Y87500
X1017919Y92500
X1024945Y83877
Y86377
X1035000Y81200
X1035900Y98800
X1044290Y87392
X1047637Y84599
Y89964
X1050983Y87392
Y92757
X1054330Y84599
Y89964
X1057676Y87392
Y92757
X1061023Y84714
Y89964
X1064369Y87392
Y92757
X1067716Y84599
Y89964
X1071062Y92757
X1074409Y84714
Y89964
X1077755Y87392
Y92757
X1081102Y84599
Y89964
X1084448Y87392
Y92757
X1087795Y84714
Y89964
X1091141Y87392
Y92657
X1094488Y84714
Y89964
X1098218Y85296
X1098300Y89900
X1101181Y84714
Y92757
X1104227Y87714
X1104177Y90314
X1107724Y84714
X1107874Y92757
X1110520Y87714
Y90314
X1114340Y84698
Y87300
Y89900
X1114316Y92500
X1119416Y84700
X1119440Y87514
Y90114
Y92714
X1124606Y84714
Y92757
X1127952Y87714
Y90414
X1131299Y84714
Y92757
X1134645Y87714
Y90414
X1137992Y84714
Y92757
X1141038Y87714
X1140988Y90314
X1144535Y84714
X1144685Y92757
X1147331Y87714
Y90414
X1151128Y92500
X1151152Y84698
Y87300
Y89900
X1156228Y84700
X1156252Y87514
Y90114
Y92714
X1161417Y84714
Y92757
X1164763Y87714
Y90414
X1168110Y84714
Y92757
X1171456Y87714
Y90414
X1174803Y84714
Y92757
X1177849Y87714
X1177799Y90314
X1181346Y84714
X1181496Y92757
X1184142Y87714
Y90414
X1187939Y92500
X1187963Y84698
Y87300
Y89900
X1193039Y84700
X1193063Y87514
Y90114
Y92714
X1198228Y84714
Y92757
X1201574Y87714
Y90414
X1204921Y84714
Y92757
X1208267Y87714
Y90414
X1211614Y84714
Y92757
X1214874Y87374
X1218157Y84714
X1218307Y92757
X1220953Y87714
Y90414
X1224774Y84698
Y87300
Y89900
X1224750Y92500
X1229850Y84700
X1229874Y87514
Y90114
Y92714
X1235039Y84714
Y92757
X1238385Y87714
Y90414
X1241732Y84714
Y92757
X1245078Y87714
Y90414
X1248425Y84757
Y92657
X1251771Y84757
Y92599
X1255118Y84757
Y92599
X1258464Y84757
Y92599
X1261811Y84757
Y92599
X1265157Y84757
Y92599
X1268581Y92706
X1270350Y98300
X1275470Y99390
X1288381Y97320
X1291381
X1295581Y94320
Y97320
X1298754Y83233
X1301219Y89141
X1308983Y93814
X1308972Y96742
X1309700Y83300
X1311559Y91431
X1311551Y93952
X1317195Y87098
X1317300Y84600
Y89600
X1320000Y85500
X1323000Y83000
X1328500Y92500
X1330300Y83500
X1335120Y94450
X1336500Y81100
X1336900Y89896
X1338500Y96000
X1343500Y87500
X1344000Y83000
X1347000Y87500
X1347500Y83000
X1348615Y96239
X1351500Y83000
X1353500Y96959
X1355500Y83000
X1357000Y86640
X1359500Y83000
X1360700Y86550
X1361634Y95519
Y97919
X1364700Y86550
Y96440
X1366100Y82500
X1367700Y86450
X1370100Y82500
X1372300Y86400
X1374808Y99366
X1375412Y92182
X1378464Y91979
X1403264Y82000
X1403746Y91680
X1405149Y93679
X1406264Y82000
X1406746Y91680
X1407960Y93800
X1409264Y82000
X1453700Y83750
X1453809Y94639
X1455347Y92065
X1457000Y82000
X1490057Y85165
X1490674Y98787
X1491164Y82923
X1498705Y99522
X1499613Y84046
X1499875Y86681
Y90481
X1500775Y98101
X1511700Y84600
X1511651Y98675
X1513013Y96546
X1513335Y92921
X1515294Y91306
X1519580Y81313
X1519599Y86117
X1523563Y93565
X1523889Y99033
X1524557Y88336
X1526744Y93265
Y98265
X1541670Y87760
X1541800Y99700
X1541900Y97300
X1541988Y90207
Y92707
X1544180Y91660
X1545250Y88360
X1546370Y84180
X1554800Y98200
X1556200Y94800
X1558100Y98200
X1572586Y95639
X1572634Y98546
X1573060Y84120
X1574780Y90992
X1575959Y84198
X1577269Y95344
X1583374Y81319
X1583621Y87213
X1587359Y84348
X1588700Y94288
X1589900Y84422
X1590949Y97850
X1591270Y93940
X1595335Y98135
X1596900Y84500
X1597867Y93900
X1599500Y84500
X1602000
X1606579Y86726
X1606730Y84230
X1614169Y95004
X1614997Y84403
X1617347Y94581
X1620900Y81300
X1625075Y80182
X1625451Y84288
X1628788Y97800
X1630826Y88087
X1632000Y83000
X1632006Y94500
X1632020Y97871
X1635900Y83000
X1638500Y96500
X1641600
X1643500Y80400
X1659000Y85500
Y88000
X1659038Y95111
X1660400Y98500
X1661900Y92400
X1663000Y81600
X1664500Y99000
X1665500Y81600
X1667000Y88000
X1668000Y81600
X1669000Y92000
X1670250Y87873
X1670500Y81600
X1673000
X1674749Y87050
X1675062Y91219
X1675500Y81600
X1677573Y86930
X1677649Y90301
X1678000Y81600
X1680139Y99073
X1686876Y98962
X1689250Y86000
X1689368Y98750
X1692285Y94612
X1692573Y85833
X1695300Y94712
X1696870Y86093
X1696907Y99077
X1697800Y94612
X1700300Y94703
X1704824Y90049
X1708610Y85121
X1709184Y88811
X1713900Y87900
X1716900
X1731350Y92140
X1733900Y92200
X1746491Y95650
X1754703Y84053
X1757395Y84794
X1757772Y90174
X1760364Y85136
X1765900Y83700
X1767250Y89500
Y94500
Y99500
X1771707Y86500
X1788200Y85000
Y89000
Y93000
X1788448Y98820
X1798454Y82256
X1800000Y80000
X1821350Y98270
X1824240Y83680
X1827000Y87000
Y94550
X1827100Y81600
X1827150Y97800
X1842250Y84000
Y90750
X1843107Y97988
X1846800Y95400
X1847000Y86500
X1849426Y90700
Y95500
X1852600Y97500
X1856778Y87397
X1856873Y91200
X1860815Y91184
X1860995Y84509
X1864195
X1864208Y87724
X1864153Y91241
X1878550Y99470
X1882550
X1907929Y84793
X1907907Y87223
X1907986Y82393
X1918002Y98902
X1918113Y93576
X1918210Y96103
X1918379Y84788
X1918352Y89300
X1923300Y94300
X1923329Y99475
X1933914Y96040
X1934256Y99459
X1937728Y99441
X1943660Y98180
X1946570Y90363
Y92863
X1946670Y85363
Y87863
X1946770Y98150
X1948472Y80362
X1949170Y90363
Y92863
X1949270Y85363
Y87863
X1949610Y95513
X1951670Y90363
Y92863
X1951770Y85363
Y87863
X1952110Y95513
X1952440Y98520
X1954169Y84111
X1954391Y92513
X1954861Y95163
X1956891Y92513
X1957361Y95163
X1965679Y80469
Y82969
X1968179Y80469
X1970679
X1967580Y104721
X1952726Y102950
X1946500Y104974
X1942637Y100877
X1932998Y119438
X1923837Y118800
X1914500Y113300
X1914152Y115928
X1908715Y104512
X1906871Y106049
X1906467Y115305
X1906414Y118004
X1898102Y107325
X1897536Y114600
X1890974Y105600
X1887830Y102227
X1887497Y105444
X1887300Y115700
X1885102Y101134
X1881500Y115700
X1881165Y105561
X1876001Y105438
X1875700Y115700
X1874258Y103196
X1871855Y104188
X1866606Y109967
X1864904Y114735
X1857110Y113600
X1856700Y110167
X1853317Y108197
X1851341Y106358
X1830316Y102163
X1824990Y103620
X1814900Y116900
X1812743Y104395
X1810245Y104500
X1810100Y114700
X1808313Y111705
X1807745Y104500
X1803400Y114000
X1796059Y104402
X1788648Y101490
X1783252Y109044
X1777000Y115750
X1770850Y109500
X1767250Y104500
X1765015Y119100
X1761300
X1758100
X1754600Y109200
X1748425Y119190
X1678400Y103000
X1674800Y103100
X1672200Y112200
X1648000Y100597
X1600000Y104243
X1598300Y116477
X1594452Y111377
X1589622Y112876
X1588500Y106788
X1588000Y100500
X1585500Y101000
X1582500Y109900
X1580275Y101041
X1578000Y113000
X1576606Y104392
X1573153Y103721
X1572395Y110754
X1558189Y107067
X1558136Y100877
X1554627
X1549187Y104713
X1549000Y115571
X1548955Y101358
X1542100Y119200
X1541765Y114000
X1541421Y106742
X1526813Y108958
X1526513Y115769
Y103958
X1524284Y112773
X1523950Y104050
X1523756Y108762
X1523557Y116165
X1518376Y111499
X1518438Y100926
X1513935Y116343
X1513879Y113349
X1513935Y108332
Y104532
X1511635Y114535
X1511650Y109400
Y103400
X1501700Y103300
X1501603Y108500
X1500455Y114388
Y110933
X1498810Y108290
X1498660Y102746
X1497699Y112140
X1496658Y115088
X1490178Y112315
X1489780Y105820
X1489053Y103325
X1483366Y115902
X1482300Y118400
X1474717Y110370
X1473200Y118300
X1452648Y103788
X1452232Y109500
X1450973Y112225
X1404200Y119200
X1402500Y116300
X1398600Y116500
X1397952Y105998
X1397994Y103350
X1397193Y112602
X1396780Y119080
X1395347Y106040
X1395326Y103413
Y100913
X1394253Y116989
X1394310Y111506
X1394298Y108548
X1391359Y108496
X1388100Y108500
X1384600
X1381359Y108496
X1377308Y106866
Y104366
Y101866
X1376669Y118763
X1376100Y116100
X1374808Y106866
Y104366
Y101866
X1373850Y117450
Y114450
X1371500Y101000
X1357700Y108400
Y104950
X1352200Y108400
Y104950
X1345500Y107529
X1345257Y100000
X1345000Y104500
X1326800Y107250
Y104250
X1325125Y100001
X1323800Y107250
Y104250
X1322628Y100134
X1302526Y119102
X1302504Y116700
Y114300
Y111700
X1301770Y101300
X1286116Y118932
Y115932
X1277660Y109450
X1277600Y106200
X1277230Y117570
X1277100Y114800
X1271490Y104700
X1271500Y102100
X1268576Y117788
X1268600Y104700
X1268500Y102100
X1264550Y114670
X1261030Y105350
X1260500Y117500
X1257850Y116950
Y113850
X1257800Y110900
X1255400Y108000
X1254300Y105200
X1251980Y106960
X1237400Y103100
X1208267Y110014
Y107314
X1204921Y112357
Y104314
X1201574Y110014
Y107314
X1198228Y112357
Y104314
X1193089Y112865
Y110264
X1193063Y107655
X1193076Y105051
X1187963Y113114
Y110514
X1187989Y107865
Y105265
X1184142Y109564
Y106964
X1181496Y112357
X1181346Y104314
X1177799Y109914
X1177849Y107314
X1174742Y112357
Y104314
X1170721Y109564
Y106964
X1168075Y104314
X1167925Y112357
X1164428Y109564
Y106964
X1161632Y112357
Y104314
X1156278Y112865
Y110264
X1156252Y107655
X1156265Y105051
X1151152Y113114
Y110514
X1151178Y107865
Y105265
X1147331Y109564
Y106964
X1144685Y104314
X1144535Y112357
X1141038Y109564
Y106964
X1138242Y112357
Y104314
X1077304Y105800
Y103100
X1071111Y105800
X1071120Y103116
X1064428Y105800
X1064427Y103116
X1057734Y105750
Y103116
X1050983Y105800
Y103116
X976700Y103021
X976200Y105600
X974100Y103500
X963245Y105725
X953786Y107684
X953800Y105000
X950600Y112300
X950590Y109700
X947250Y107700
X947243Y105084
X944497Y110927
X938758Y112865
Y110264
X938732Y107655
X938745Y105051
X933658Y107865
Y105265
X933632Y113114
Y110514
X929811Y109534
Y106934
X927165Y112327
X927015Y104284
X923468Y109884
X923518Y107284
X920472Y112327
Y104284
X917125Y109984
Y107284
X913779Y112327
Y104284
X910432Y109984
Y107284
X907086Y112327
Y104284
X901947Y112865
Y110264
X901921Y107655
X901934Y105051
X896821Y113114
Y110514
X896847Y107865
Y105265
X893000Y109534
Y106934
X890354Y112327
X890204Y104284
X886657Y109884
X886707Y107284
X883661Y112327
Y104284
X769100Y102900
X766500
X756800Y102000
X752900Y101000
X746600Y103900
X744200Y102800
X741700Y102000
X704419Y104448
X701953Y104902
X699400Y105060
X698600Y102600
X696832Y104986
X696100Y102700
X694459Y105382
X693600Y103100
X691810Y105540
X677896Y119093
X676494Y116940
X674896Y119093
X673566Y116724
X671249Y118744
X670503Y115884
X668665Y118185
X661053Y115971
X658490Y115432
X654558Y115101
X650307Y115518
X647809Y116121
X645311Y116724
X642899Y117112
X640043Y117728
X633800Y119000
X622200Y112200
X620054Y114096
X618800Y100100
X617400Y115800
X616167Y118627
X616115Y108339
X613602Y118047
Y109247
X608600Y103000
X605028Y119000
X604977Y110200
X603163Y103971
X602100Y109600
X558659Y110014
Y107314
X555313Y112357
Y104314
X551966Y110014
Y107314
X548620Y112357
Y104314
X543481Y112865
Y110264
X543455Y107655
X543468Y105051
X538355Y113114
Y110514
X538381Y107865
Y105265
X534534Y109564
Y106964
X531888Y112357
X531738Y104314
X528191Y109914
X528241Y107314
X525134Y112357
Y104314
X521113Y109564
Y106964
X518467Y104314
X518317Y112357
X514820Y109564
Y106964
X512024Y112357
Y104314
X506670Y112865
Y110264
X506657Y105051
X506644Y107655
X501570Y107865
Y105265
X501544Y113114
Y110514
X497723Y109564
Y106964
X495077Y104314
X494927Y112357
X491430Y109564
Y106964
X488634Y112357
Y104314
X427696Y105800
Y103100
X421503Y105800
X421512Y103116
X414820Y105800
X414819Y103116
X408126Y105750
Y103116
X401375Y105800
Y103116
X327092Y103021
X326592Y105600
X324492Y103500
X313637Y105725
X304178Y107684
X304192Y105000
X300992Y112300
X300982Y109700
X297642Y107700
X297635Y105084
X294889Y110927
X289150Y112865
Y110264
X289124Y107655
X289137Y105051
X284024Y113114
Y110514
X284050Y107865
Y105265
X280203Y109534
Y106934
X277557Y112327
X277407Y104284
X273860Y109884
X273910Y107284
X270864Y112327
Y104284
X267517Y109984
Y107284
X264171Y112327
Y104284
X260824Y109984
Y107284
X257478Y112327
Y104284
X252339Y112865
Y110264
X252313Y107655
X252326Y105051
X247213Y113114
Y110514
X247239Y107865
Y105265
X243392Y109534
Y106934
X240746Y112327
X240596Y104284
X237099Y107284
X237049Y109884
X234053Y112327
Y104284
X120533Y109535
X120197Y106587
X104424Y110833
X98420Y112198
X68654Y118680
X68000Y111000
X66600Y102360
X65405Y118730
X65384Y109750
Y104750
X63582Y116409
X62502Y105100
X62422Y109413
X60801Y102750
X60700Y116750
Y111750
X51569Y118750
X51381Y109750
Y104750
X48800Y118900
X48700Y109600
X48600Y104900
X46900Y116750
Y111750
Y102750
X44300Y102700
X44200Y116800
Y111500
X37037Y138425
X44200Y130700
Y139400
X44300Y125600
X46900Y125750
Y130750
Y139750
X48800Y137600
X48900Y123500
Y132600
X51569Y123750
Y132750
Y137750
X60831Y125750
Y130750
Y139750
X62524Y123395
X63737Y130602
X65405Y123730
X65687Y132750
Y137750
X68584Y123900
X68592Y132600
X68632Y137800
X77730Y126860
X77790Y121030
X79670Y132300
X85250Y127680
X91913Y121318
X107254Y128041
X109622Y128879
X112664Y128795
X117682Y130387
X117652Y132792
X120138Y130408
X120117Y132865
X605300Y124600
X609482Y124568
X624500Y129400
X626900Y128300
X630000Y126572
X633580Y125560
X635951Y127419
X636481Y124951
X638800Y126700
X639100Y124200
X641950Y125750
X642673Y139811
X643674Y123573
X644950Y125750
X647120Y122700
X648690Y125590
X650120Y122700
X651920Y125750
X653111Y121550
X656111
X657900Y123650
Y126650
X660900Y123650
Y126650
X679900Y128200
X682400Y127085
X684900
X1240000Y129500
X1246251Y130066
X1247326Y122802
X1248616Y133817
X1249025Y130460
X1250200Y122900
X1251344Y127925
X1254024Y128013
X1257800Y120800
X1260737Y133877
X1263798Y133493
X1266200Y122500
X1268900
X1271500
X1277100Y122670
X1286000Y132000
Y134500
Y137000
Y139500
X1288500Y132000
Y134500
Y137000
Y139500
X1293700Y121800
X1301900Y124400
X1306900Y131744
X1323026Y133323
X1323600Y123450
Y126450
X1326026Y133323
X1326600Y123450
Y126450
X1356230Y126500
X1359230
X1360730Y129000
X1362230Y126500
X1363730Y129000
X1365230Y126500
X1366730Y129000
X1368230Y126500
X1369730Y129000
X1373850Y120450
Y123450
X1376100Y124950
X1376669Y121763
X1380700Y125450
Y128450
X1383700Y125450
Y128450
X1386700Y125450
Y128450
X1391700Y122950
Y125950
Y128950
X1394700Y122950
Y125950
Y128950
X1399400Y126400
X1400300Y121500
X1401200Y124300
X1451590Y138750
X1468590Y131200
X1468755Y128478
X1472500Y123700
X1473096Y120999
X1473100Y128950
Y131900
X1482455Y124222
X1483093Y130796
X1483366Y120746
X1484113Y128513
X1485210Y134837
X1485755Y131671
X1496726Y120588
X1499618Y124520
X1500700Y127250
X1500806Y133339
X1511634Y121195
X1511664Y133603
X1511660Y138510
X1511800Y127050
X1513935Y120143
X1514425Y134180
Y137980
X1514600Y126650
X1518514Y130991
X1520150Y127600
X1523813Y120546
X1524000Y123300
X1524744Y133656
X1524900Y139100
X1526513Y120769
X1526728Y124168
X1529449Y137408
X1530101Y132671
X1531726Y123800
X1531678Y135284
X1541390Y136498
X1541434Y139871
X1542000Y126246
X1542685Y133321
X1542900Y121700
X1552171Y133000
X1553353Y124209
X1553500Y121000
X1554800Y129100
X1554945Y133400
X1555000Y139000
X1555676Y123283
X1558100Y124427
Y128926
Y133526
Y138025
X1558383Y121500
X1563108Y126423
X1567520Y133354
X1567968Y136682
X1567981Y139607
X1573121Y120649
X1574197Y127915
X1579310Y128604
X1579290Y131104
X1587620Y135921
X1589200Y121800
X1589880Y134851
X1590800Y137800
X1593241Y134295
X1593500Y137800
X1593756Y129048
X1595522Y127278
X1598449Y120760
X1778000Y120000
X1784750Y124000
X1787373Y120188
X1788000Y129000
X1796500Y120000
X1800000Y132627
X1800792Y122691
X1803509Y128500
X1807509
X1807818Y124179
X1808226Y136171
X1813118Y127976
X1815026Y121478
X1815883Y133277
X1816418Y127976
X1818383Y133277
X1845469Y135500
X1848100Y134750
X1854115Y131121
X1854250Y138600
X1854962Y133613
X1857020Y126619
Y129619
X1857250Y138600
X1861015Y130815
X1860969Y133769
Y136369
X1862400Y124500
X1865577Y124450
X1867280Y135406
X1872254Y138618
X1875700Y121500
Y127300
X1878753Y139893
X1878950Y137400
X1881500Y121500
Y127300
X1887300Y121500
Y127300
X1894834Y139286
X1895060Y136099
X1897536Y120510
X1897507Y124450
X1911231Y137097
X1911440Y128840
X1919195Y134396
X1919514Y131701
X1919702Y125920
Y128501
X1926892Y121203
X1927810Y123544
X1927918Y126156
X1928100Y136078
X1929736Y128337
X1929756Y131037
X1934544Y127957
X1940700Y136300
X1943752Y137548
X1947078Y139300
X1973328Y147303
X1973004Y143120
X1971200Y152500
X1966700Y152400
X1965400Y149700
X1964382Y147318
X1963400Y141100
X1962800Y149300
Y143700
X1951700Y141000
X1950983Y147344
X1950934Y143730
X1949389Y152083
X1947000Y142600
X1944600Y151700
X1944609Y149184
X1940500Y157600
X1937900Y153600
X1937000Y150000
X1936187Y144013
X1934000Y147100
X1929711Y155759
X1929000Y158600
X1926952Y156049
X1927000Y152200
X1925358Y140685
X1923800Y151000
X1921264Y153000
X1921199Y140499
X1919484Y149500
X1916310Y149676
X1915030Y147250
X1914690Y152580
X1913392Y149381
X1912100Y142600
X1911961Y153000
X1909216Y142812
X1908327Y149353
X1905540Y153000
X1905092Y150170
X1904215Y142812
X1904136Y140160
X1900100Y145100
X1899855Y142122
X1895800Y149200
X1895673Y151800
X1894855Y142122
X1893640Y147042
X1888639
X1886299Y153928
X1886000Y156700
X1886050Y151431
X1885700Y141200
X1885400Y147000
X1881324Y153250
X1878096Y152843
X1875600Y156300
X1875425Y152925
X1872400Y144619
X1872340Y147236
X1871521Y153593
X1869668Y146750
X1869000Y153900
X1863908Y140992
X1861932Y146431
X1857919Y156123
X1857849Y148079
X1854663Y158248
X1850700Y156000
X1848590Y141360
X1848532Y144360
X1846663Y158248
Y153748
X1839873Y159358
X1839941Y156858
X1839667Y151994
X1837090Y149830
X1828960Y153010
X1828340Y149960
X1827500Y144900
X1824509Y143653
X1821348Y143437
X1820648Y155537
X1818500Y159500
X1816348Y155537
X1815348Y143437
X1811348Y143448
X1809810Y155858
X1807166Y147401
X1803058Y143733
X1801366Y151937
X1800420Y148240
X1800264Y143789
X1790100Y154000
X1787500Y155170
X1780720Y153850
X1776828Y155211
X1768886Y156173
X1758650Y158650
X1750189Y159550
X1745689
X1741189
X1736689
X1732189
X1727689
X1723189
X1718689
X1714189
X1701455Y153083
X1698927Y153139
X1657835Y156436
X1577950Y152600
X1577770Y149519
X1577700Y155353
Y140149
X1576506Y143416
X1574000Y152100
Y149500
X1557981Y141470
X1553500Y157000
X1541831Y149030
X1541413Y155259
X1541351Y151900
X1533132Y158068
X1532923Y144518
X1531985Y147000
X1531700Y155600
X1526310Y142190
X1523719Y149488
X1515358Y151743
X1513500Y153800
X1513136Y157081
X1513023Y140630
X1510184Y142614
X1505673Y146346
X1503466Y142486
X1502000Y147500
X1500703Y158233
X1500643Y154819
X1496150Y148115
X1496038Y154229
X1495848Y150600
X1494939Y159500
X1493069Y152834
X1492013Y155610
X1490900Y146600
X1488800Y145000
X1488350Y149450
X1488300Y158300
X1476761Y157400
Y152725
X1475200Y142600
X1473354Y153246
X1469747Y148276
X1451273Y148905
X1451233Y146405
X1451198Y143761
X1451228Y141261
X1451021Y151626
X1438348Y155908
X1401300Y149600
X1385100Y155000
Y150000
Y145000
X1380100Y155000
Y150000
Y145000
X1375100Y155000
Y150000
Y145000
X1370100Y155000
Y150000
Y145000
X1365100Y155000
Y150000
Y145000
X1360100Y155000
Y150000
Y145000
X1355100Y155000
Y150000
Y145000
X1350100Y155000
Y150000
Y145000
X1345100Y155000
Y150000
Y145000
X1340100Y155000
Y150000
Y145000
X1335100Y155000
Y150000
Y145000
X1330100Y155000
Y150000
Y145000
X1327900Y142918
X1320500Y145000
X1315100
X1310175Y154696
X1310098Y150040
X1299907Y159808
X1298400Y144500
X1295700Y144450
X1295172Y153670
X1295240Y149830
X1293543Y151756
X1293335Y148177
X1291772Y153694
X1291735Y150061
X1287790Y156575
X1278030Y148510
X1278000Y145780
X1272100Y141603
X1269810Y154398
X1268236Y141938
X1266646Y150540
X1265828Y140568
X1264700Y154800
X1264146Y150584
X1262569Y147201
X1261800Y154973
X1261546Y150584
X1259950Y144650
X1252437Y140192
X1252000Y145300
X1243948Y154916
X1240927Y154932
X1240010Y144754
X1240022Y141773
X1237704Y148423
X758400Y159200
Y156200
X746000Y150500
X740650Y158800
X740718Y150957
X730600Y154984
X725650Y155000
X720700Y154750
X715550Y158880
X715505Y155076
X710550Y158880
X705550
X675600Y150000
Y144900
X664700Y142800
X661700Y142300
X658055Y141493
X654555Y142193
X651055Y142893
X647555Y143643
X644055Y144493
X639173Y140618
X635673Y141318
X632173Y142018
X628673Y142718
X91306Y157194
X87200Y152374
X78950Y152810
X75660Y152380
X70800Y151400
X68098Y151473
X63878Y144800
X63888Y140064
X63098Y151473
X60831Y144750
X60300Y151500
X52500Y152000
X51309Y154356
X47309
X46900Y144750
X44600Y154100
X44300Y144800
X39109Y154901
X-19210Y162529
X-15768Y161922
X-12861Y163165
X61402Y177773
X64187Y176332
X77650Y178150
X99250Y160370
X644750Y175650
X660600Y175000
X735600Y164900
X740650Y164800
X747600Y161450
X1220580Y179810
X1221767Y175858
X1226780Y178980
X1229780
X1232780
X1233902Y173337
X1240309Y161900
X1241381Y172040
X1242800Y175200
X1244410Y173150
X1246655Y176395
X1246910Y173150
X1252800Y176000
X1255200
X1259200Y168350
X1263300Y169450
X1267050Y169800
X1267800Y161800
X1271400Y161900
X1295500Y159970
X1300300Y169900
X1303838Y169922
X1305171Y164767
X1306363Y169928
X1310061Y165235
X1320100Y165000
Y170000
X1325100Y165000
Y170000
X1330100Y160000
Y165000
Y170000
X1335100Y160000
Y165000
Y170000
X1340100Y160000
Y165000
Y170000
X1345100Y160000
Y165000
Y170000
X1350100Y160000
Y165000
X1355100Y160000
Y165000
Y170000
X1360100Y160000
Y165000
Y170000
X1365100Y160000
Y165000
Y170000
X1370100Y160000
Y165000
Y170000
X1375100Y160000
Y165000
Y170000
X1380100
X1385100Y160000
Y165000
Y170000
X1390100Y160000
Y165000
Y170000
X1399100Y166900
X1402020Y165561
X1440124Y166180
X1440150Y175550
X1450532Y178372
X1451366Y165296
X1451427Y167818
X1451365Y170318
X1451386Y173499
X1451365Y176014
X1454070Y163360
X1454660Y166200
X1468700Y163100
X1471388Y173700
X1473888Y173721
X1477388Y172988
X1488300Y161700
X1488900Y172576
X1489015Y179832
X1489088Y176680
X1492500Y176887
X1492469Y179387
X1492597Y172636
X1493200Y162700
X1494783Y177907
X1496713Y174853
X1497493Y162078
X1502192Y164871
X1504706
X1510638Y166240
X1527500Y167726
X1531565Y176645
X1535065Y164300
X1537298Y162703
X1545023Y161675
X1552051Y172053
X1553500Y165400
X1557634Y175948
X1558042Y172448
X1561538Y174649
X1562079Y163580
X1562150Y160700
X1566858Y175192
X1568488Y164058
X1570294Y167384
X1572817Y169910
X1591800Y164900
X1595291Y166423
X1614000Y177800
X1651000Y178628
X1663400Y179475
X1674019Y175990
X1674455Y169991
Y172658
X1677605Y169986
X1677600Y172700
X1688046Y174447
X1691439Y174354
X1695734Y164676
X1700836Y161268
X1703610Y161214
X1708250Y164950
X1708350Y175050
X1713596Y175795
X1719100Y176000
X1719250Y179150
X1723189Y176012
X1726700Y179400
X1727193Y176525
X1732193
X1733178Y179574
X1739377Y179374
X1739792Y176525
X1744792
X1745777Y179574
X1749295Y176104
X1751975Y179374
X1752390Y176525
X1757390
X1758375Y179574
X1764673Y179374
X1764988Y176525
X1769988
X1770973Y179574
X1777172Y179374
X1777587Y176525
X1778900Y165800
X1782587Y176525
X1783572Y179574
X1785500Y164000
Y168000
X1787000Y175500
X1789870Y179374
X1790185Y176525
X1792748Y171937
X1795185Y176525
X1795348Y172037
X1796170Y179574
X1797848Y172037
X1802369Y179374
X1802784Y176525
X1807440Y162030
Y165530
Y169030
X1807784Y176525
X1808769Y179574
X1815000Y179300
X1815382Y176525
X1816125Y169492
X1816348Y163437
X1820382Y176525
X1820648Y163437
X1821261Y170012
X1821367Y179574
X1824200Y176900
X1827565Y179174
X1833388Y179500
X1833629Y170807
X1834103Y176021
X1836100Y179700
X1836900Y165800
X1836932Y170486
X1840900Y179700
X1845700
X1846163Y168448
X1854900Y175900
X1855000Y167100
X1857400Y175900
X1862000Y177500
X1863750Y163750
X1865100Y174600
X1868375Y171900
X1875066Y175782
X1876832Y173919
X1883800Y179100
X1883930Y176137
X1885465Y166285
X1886200Y161000
X1886400Y170000
Y172600
Y178700
X1900700Y167290
Y172990
X1900740Y178720
X1906400Y167290
X1906440Y178720
X1906500Y173100
X1912230Y167330
Y173030
X1912190Y178870
X1927500Y170400
X1928218Y175443
X1928249Y178179
X1929700Y163400
X1930300Y170147
X1931065Y175520
X1931639Y178396
X1935600Y176300
X1938400Y178200
X1939316Y173600
X1939550Y165600
X1940240Y169970
X1940647Y161600
X1944550Y176450
X1945156Y160236
X1950981Y168064
X1950994Y173745
X1961472Y165760
X1963092Y167936
X1965057Y176447
X1965973Y166190
X1966542Y179606
X1972598Y165236
X1965900Y184600
X1963300Y191000
X1953200Y195530
X1952717Y198614
X1950981Y191218
X1944611Y193400
X1944500Y183900
X1944300Y190200
X1939400Y198400
X1939200Y194300
X1935600Y198700
X1934100Y193400
X1932837Y186700
X1931483Y199350
X1929090Y193190
X1925400Y196300
X1925000Y192000
X1921500Y193600
X1917024
X1905074Y198163
X1901100Y194200
X1896710Y194380
X1889400Y191200
X1884400Y183700
X1884000Y188100
X1883539Y199813
X1882452Y195888
X1875700Y184800
X1864464Y198466
X1864000Y184900
X1863650Y189750
X1861243Y183100
X1858686Y180377
X1857044Y186292
X1854868Y184667
X1854942Y181655
X1847000Y198600
X1830415Y196567
X1828700Y198800
X1826682Y196841
X1821682
X1819457Y198872
X1816266Y198772
X1814041Y196841
X1809041
X1806821Y198600
X1804166Y198472
X1801441Y196841
X1796441
X1794216Y198872
X1791066Y198772
X1788841Y196841
X1783841
X1781616Y198872
X1778466Y198772
X1776241Y196841
X1771241
X1769016Y198872
X1765866Y198772
X1763668Y196843
X1758668
X1756600Y198800
X1753311Y198700
X1751082Y196843
X1746082
X1744000Y198800
X1740900
X1738563Y196776
X1733563
X1731216Y198872
X1730400Y195850
X1728616Y198872
X1719000Y190500
X1714528Y190189
X1713000Y185000
X1709900Y187300
X1707100Y188300
X1705666Y198055
X1702500Y187000
X1702400Y193450
X1702450Y190000
X1687950Y186150
X1686183Y191250
X1683484Y190908
X1682950Y184140
X1681352Y196092
X1680370Y185900
X1680450Y183401
X1676924Y196731
X1674912Y183000
X1674066Y196666
X1671688Y182925
X1669849Y193067
X1667140Y182300
X1664321Y195244
X1660800Y181900
X1658082Y195298
X1655209Y181761
X1655031Y184505
X1650600Y186300
X1650300Y195251
X1648349Y182276
X1647852Y197374
X1644433Y185415
X1644290Y196383
X1643887Y181841
X1642457Y186948
X1641800Y184400
X1639258Y185620
X1637870Y197577
Y195077
X1635351Y185444
X1635112Y195181
X1635100Y182800
X1634069Y197454
X1632590Y195344
X1630836Y197560
X1628950Y195344
X1627326Y182759
X1625524Y184531
X1622248Y185060
X1620036Y196186
X1619500Y184944
X1618500Y181680
X1615553Y184908
X1613053Y184949
X1610554Y184877
X1608056Y184771
X1605250Y197250
X1603300Y185100
X1602185Y180709
X1598950Y180300
X1598006Y192421
X1595800Y180300
X1593218Y191776
X1587549Y192000
X1582249Y191716
X1571501Y180031
X1566486Y181270
X1561925Y192675
X1557979Y188844
X1557787Y192236
X1549693Y196707
X1548178Y190880
X1546000Y197400
X1543100Y184128
X1535399Y190920
X1535425Y188016
X1519243Y191627
X1517328Y186208
X1515060Y192443
X1512500Y199837
X1511100Y186275
X1510800Y193330
X1499800Y199300
X1492136Y199125
X1483523Y181100
X1478089Y182650
X1474883Y182275
X1470382Y188372
X1458908Y187699
X1458569Y192143
X1446331Y197285
X1442251Y180818
X1418300Y199900
X1281799Y193190
X1269254Y197923
X1267554Y195923
X1267486Y199691
X1265786Y197691
X1265570Y194510
X1264180Y199510
X1263804Y196318
X1263080Y191320
X1263040Y193930
X1262018Y197959
X1261220Y195650
X1260260Y199862
X1260140Y191670
X1259518Y197459
X1259360Y193950
X1257770Y199150
X1257601Y195655
X1257210Y192340
X1255833Y197423
X1255310Y193850
X1254065Y199191
X1253521Y195666
X1252930Y193270
X1251940Y197530
X1251089Y194810
X1250235Y199342
X1249571Y196718
X1247803Y198486
X1241712Y187710
X1232780Y181980
X1229780
X1226914Y184708
X1226780Y181980
X1226500Y199800
X1220167Y194407
X1210000Y192500
X1209033Y183907
X1125300Y199900
X1104871Y198050
X1091351Y199841
X1084591Y198931
X1071072Y199583
X1054000Y199100
X1045904Y197359
X1042506Y195041
X1027875Y193507
X1007595
X983936Y199108
X967036Y193507
X951256Y194841
X947887Y199360
X941127
X934367
X813700Y198900
Y195600
X804470Y186814
X799620Y186547
X799300Y199100
Y195600
X798337Y181216
X769044Y191348
X767692Y185654
X767476Y188323
X766368Y183636
X765227Y186164
X765007Y188583
X763881Y184103
X762667Y186186
X762533Y188626
X760258Y186077
X760084Y188508
X757654Y188464
X755248Y188368
X752708Y188455
X750167Y188490
X747469Y188368
X744928Y188438
X742091Y188333
X739641Y190634
X739359Y188125
X737536Y192392
X737319Y189766
X735626Y187965
X733564Y189288
X731155Y189256
X727776Y188811
X724888Y188930
X722117Y195399
X719686Y195421
X716557Y198557
X716480Y194700
X714137Y195682
X711886Y194714
X709400Y195763
X709341Y190507
X709200Y198700
X707529Y193200
X705292Y195729
X704907Y191638
X701956Y195294
X701129Y192106
X697746Y193205
X697568Y196197
X691583Y196624
X689033
X686533
X613773Y196796
X610273Y197496
X606773Y198196
X603273Y198896
X599773Y199596
X475692Y199900
X462023Y198327
X455263Y198050
X441743Y199841
X434983Y198931
X421464Y199583
X404392Y199100
X396296Y197359
X392898Y195041
X334328Y199108
X317428Y193507
X301648Y194841
X298279Y199360
X291519
X284759
X162800Y195600
X156954Y192872
X156928Y190053
X156294Y187625
X154454Y193021
X154130Y190186
X153788Y187309
X151810Y192670
X151359Y187700
X151300Y190200
X150000Y199850
Y194850
X148900Y190100
Y180400
X148800Y187700
Y185300
Y182900
X124340Y197750
X117600Y193805
X116900Y180500
X113800
X104820Y198800
Y195700
X104800Y185700
X102400
X100500Y188600
X99900Y185700
X97900Y194500
X97800Y197600
X97500Y185700
X90831Y184982
X87151Y184872
X86952Y181721
X86731Y189148
X76143Y183019
X73500Y191500
X61800Y191600
X61356Y181000
X61256Y186000
X97800Y200800
X102507Y211047
X104820Y202100
X106698Y215610
X107700Y211040
X115536Y213508
X115508Y216512
X122542Y214019
X124895Y212033
X125563Y218616
X127754Y211853
X128500Y218700
X130324Y212033
X137763Y215216
Y217716
X139582Y219800
X141263Y215216
Y217716
X162788Y200650
X271239Y211060
X274619Y213009
Y216909
X277999Y203260
Y207159
Y211060
Y214960
X281379Y201309
Y205210
Y213009
Y216909
X284759Y203260
Y207159
Y211060
Y214960
Y218860
X288139Y205210
Y213009
Y216909
X291519Y203260
Y207159
Y211060
Y214960
Y218860
X294899Y201309
Y209109
Y213009
X298279Y203260
Y207159
Y211060
Y214960
Y218860
X301659Y209109
Y213009
X305039Y211060
Y214960
Y218860
X308418Y201309
Y213009
X311798Y211060
Y214960
Y218860
X312918Y205210
X315178Y209109
Y213009
Y216909
X318558Y218860
X324200Y201308
X325318Y211060
X329818Y214958
X332078Y218860
X335458Y216909
X338838Y211058
Y218860
X342218Y209109
Y213009
X345598Y203260
Y207159
Y214960
X348978Y205210
Y209109
Y216909
X352357Y211060
Y214960
X355737Y205210
Y209109
Y213009
Y216909
X359117Y214960
X362497Y205210
Y209109
Y213009
Y216909
X365877Y203260
Y214960
X369257Y213009
Y216909
X372637Y207159
Y214960
X376017Y205211
Y209109
Y213009
Y216909
X379397Y214960
X382777Y201309
Y209109
Y213009
Y216909
X386157Y207159
Y214960
X389537Y209109
Y213009
Y216909
X392916Y203260
Y214960
X396296Y209109
Y213009
Y216909
X399676Y203260
Y207159
Y214960
X407706Y209109
X415634Y204496
Y208397
Y212296
Y216196
X419214Y214247
X422594Y216196
X425974Y206446
Y218147
X429353Y212296
X429354Y216196
X432733Y214247
Y218147
X436113Y212296
Y216196
X439493Y210346
Y214247
Y218147
X442873Y216196
X446253Y206446
Y218147
X449633Y212296
Y216196
X453013Y214247
Y218147
X456393Y212296
Y216196
X459773Y214247
Y218147
X463153Y216196
X466533Y206446
Y218147
X469912Y212296
X469913Y216196
X473292Y214247
Y218147
X476672Y212296
Y216196
X480052Y206447
Y214247
Y218147
X486812Y210346
Y214247
Y218147
X494692Y216196
X498072Y218147
X498350Y209900
X501452Y212296
X508212
X511592Y206447
Y210346
Y218147
X518352Y206445
Y218147
X521731Y208397
Y216196
X525111Y206447
Y214247
Y218147
X528491Y204496
Y208397
Y216196
X531871Y206447
Y210346
Y218147
X535251Y204496
Y208397
Y216196
X538631Y202247
Y206447
Y210346
Y214247
Y218147
X542011Y208396
Y216196
X545391Y210346
X547800Y201400
X548771Y212296
X552151Y214247
Y218147
X555531Y216196
X557000Y206800
X558911Y218147
X560739Y207625
X563900Y213500
X577375Y204125
X578980Y217884
X579497Y202003
X590500Y213000
Y215800
X600286Y202921
X604453Y202983
X606400Y201000
X608648Y204494
X609860Y201356
X611148Y206994
X613082Y200676
X613648Y204494
Y209494
Y211994
Y214494
Y216994
Y219494
X616148Y206994
Y211994
Y216994
X618648Y206994
Y209494
Y214494
Y219494
X621148Y206994
Y211994
Y216994
X623648Y206994
Y209494
Y211994
Y214494
Y216994
Y219494
X686533Y200124
X689033
X690861Y204317
Y208117
Y211917
Y215717
X691583Y200124
X692400Y218100
X692500Y210100
X692513Y213800
X692673Y206200
X706500Y207800
Y214900
Y217400
X706600Y201300
X706561Y204217
Y211417
Y219917
X709200Y201300
X709182Y203948
X711800Y203100
X714391Y215809
X715100Y213344
X715727Y218267
X720369Y205199
X742937Y218574
X749726Y205037
Y207537
X752226Y205037
Y207537
X754726Y205037
Y207537
X765144Y213508
X765116Y216512
X770200Y208600
X770300Y204930
X771232Y214033
X774582Y212033
X775171Y218616
X777182Y212033
X777700Y218600
X779932Y212033
X787371Y215216
Y217716
X789554Y219723
X790871Y215216
Y217716
X822400Y212400
X917467Y209109
X920847Y203260
Y207159
Y211060
X924227Y213009
Y216909
X927607Y203260
Y207159
Y211060
Y214960
Y218860
X930987Y201309
Y205210
Y213009
X934367Y207159
Y214960
Y218860
X937747Y205210
Y213009
Y216909
X941127Y203260
Y207159
Y211060
Y214960
Y218860
X944507Y201309
Y213009
X947887Y203260
Y207159
Y211060
Y214960
Y218860
X951267Y209109
X954647Y211060
Y214960
Y218860
X958026Y201309
Y213009
X961406Y211060
Y214960
Y218860
X962526Y205210
X964786Y209109
Y213009
Y216909
X968166Y218860
X973808Y201308
X974926Y211060
X979426Y214958
X981686Y218860
X985066Y216909
X988446Y211058
Y218860
X991826Y205210
X995206Y203260
Y214960
X998586Y205210
Y209109
Y216909
X1001965Y211060
Y214960
X1005345Y205210
Y209109
X1008725Y211060
Y214960
X1012105Y205210
Y209109
Y216909
X1015485Y203260
Y214960
X1018865Y216909
X1022245Y211060
Y214960
X1025625Y205211
Y209109
X1029005Y214960
X1032385Y201309
Y209109
Y216909
X1035765Y207159
Y211060
Y214960
X1039145Y209109
Y216909
X1042524Y203260
Y214960
X1045904Y209109
X1049284Y203260
Y214960
X1057314Y209109
X1065242Y204496
Y208397
Y212296
X1068822Y214247
Y218147
X1072202Y216196
X1075582Y206446
Y218147
X1078961Y212296
X1078962Y216196
X1082341Y214247
Y218147
X1085721Y212296
Y216196
X1089101Y210346
Y214247
X1092481Y216196
X1095861Y206446
Y218147
X1099241Y212296
Y216196
X1102621Y214247
Y218147
X1106001Y212296
Y216196
X1109381Y214247
X1112761Y216196
X1116141Y218147
X1119520Y212296
X1119521Y216196
X1122900Y214247
Y218147
X1126280Y212296
Y216196
X1129660Y206447
Y214247
X1136420
Y218147
X1147950Y209900
X1151060Y212296
Y216196
X1154440Y214247
X1157820Y212296
Y216196
X1161200Y206446
Y210346
Y218147
X1164580Y212296
Y216196
X1167960Y206447
Y210346
Y218147
X1171339Y208397
Y212296
Y216196
X1174719Y202547
Y206447
Y210346
Y218147
X1178099Y204496
Y208397
Y212296
Y216196
X1181479Y202547
Y206447
Y210346
Y218147
X1184859Y204496
Y208397
Y212296
Y216196
X1188239Y202247
Y206447
Y210346
Y214247
Y218147
X1191619Y208397
Y216196
X1194999Y210346
Y214247
X1197492Y201356
X1198379Y212296
Y216196
X1201759Y218147
X1205759Y206682
X1218000Y218100
X1218868Y214869
X1220702Y216708
X1221300Y205400
Y208000
X1226500Y202400
X1226785Y210403
Y213003
X1226867Y207904
X1227200Y215543
X1240452Y208240
Y210740
Y213240
Y215740
X1240500Y218200
X1242800Y204150
X1243196Y207002
X1244380Y202160
X1245014Y205405
X1246090Y200330
X1246620Y203570
X1248290Y201720
X1250625Y202804
X1252330Y201030
X1254310Y202840
X1255982Y200995
X1256810Y203340
X1258482Y201495
X1258810Y204840
X1260510Y206840
X1260620Y203130
X1262080Y209140
X1262250Y201227
X1262182Y204995
X1263680Y207160
X1263728Y211444
X1263950Y203227
X1265420Y205400
X1265450Y209263
X1265718Y201459
X1267220Y203600
X1267218Y207495
X1268930Y201820
X1268986Y205727
X1270754Y203959
X1270930Y200220
X1272522Y202191
X1320390Y216824
X1322500Y209251
X1323030Y216531
X1324938Y209251
X1326474Y216500
X1329324Y208951
X1330074Y216500
X1331824Y209051
X1333074Y216500
X1334724Y209051
X1336074Y216500
X1338224Y209051
X1344462Y209272
X1348569Y208960
X1353569
X1356926Y209100
X1359500Y209200
X1362000Y209300
X1367789Y209216
X1384671Y214832
X1396933Y215763
X1402870Y207918
X1403400Y204766
X1408247Y206270
X1422196Y218052
X1439000Y208500
X1447999Y205645
X1449847Y202322
X1472758Y216495
X1474439Y207621
X1475401Y210017
X1478611Y209695
X1479000Y207225
X1487716Y218650
X1491196Y218527
X1497237Y217281
X1507524Y218600
X1512525Y208944
X1512700Y205100
X1513900Y218000
X1516598Y203037
X1516616Y205537
X1516872Y208863
X1523400Y217900
X1535000Y207200
X1545910Y199977
X1552063Y202031
X1558000Y205100
X1583600Y207495
X1583874Y217746
X1590495Y214525
X1590525Y217033
X1592870Y217900
X1593020Y215129
X1604401Y213500
X1611761Y213507
Y216250
X1615362Y213507
X1626935Y217775
X1629595Y217725
X1635621Y208259
X1645700Y214050
X1648400Y214100
X1654015Y217239
X1655978Y207827
X1659643Y213505
X1660440Y200789
X1663566Y213009
X1664390Y201163
X1667356Y213096
X1671556Y208379
X1673530Y209974
X1673800Y201070
X1676750Y206050
X1687550Y213751
X1731260Y209600
X1733484Y211631
X1738484
X1740709Y209600
X1743900Y209700
X1746125Y211631
X1751125
X1753400Y209900
X1756000Y210000
X1758725Y211631
X1763725
X1765950Y209600
X1769100Y209700
X1771325Y211631
X1776325
X1778550Y209600
X1781700Y209700
X1783925Y211631
X1788925
X1791150Y209600
X1794300Y209700
X1796526Y212231
X1801526
X1803072Y209728
X1807751Y209586
X1809125Y212231
X1814125
X1815670Y209728
X1820349Y209586
X1821685Y212161
X1826685
X1828950Y209600
X1832274Y209734
X1834400Y216900
X1839500Y212700
X1847200Y202050
X1847699Y212946
X1850723Y219250
X1850876Y212946
X1855670Y206430
X1856874Y219443
X1858500Y200100
X1858470Y206335
X1859604Y213206
X1861497Y211481
X1864170Y211869
X1864637Y201861
X1868843Y207920
X1871708Y213442
X1872100Y207900
X1874236Y213800
X1876700Y207600
X1877517Y217988
X1877880Y203780
X1878789Y213663
X1883350Y202410
X1883800Y210575
Y213436
X1884340Y217866
X1886093Y202184
X1886800Y210600
X1886952Y213125
X1891880Y204370
X1892791Y200069
X1893238Y208042
X1895100Y201770
X1895614Y204785
X1897450Y213951
Y216551
X1903150Y217250
X1903524Y208156
X1903917Y201472
X1904042Y204895
X1908967Y201609
X1909186Y211906
X1909438Y204307
X1909421Y208805
X1910123Y217349
X1917568Y201215
X1918143Y219848
X1918489Y212513
X1926000Y212400
X1927064Y207564
X1928400Y212500
X1930500Y209464
X1933898Y216707
X1937100Y206800
X1939300Y204300
X1943200Y214800
X1943217Y217645
X1943500Y209500
X1956901Y215241
Y218391
X1957334Y201269
X1967817Y201029
X1946105Y230344
X1944925Y226001
X1944463Y228458
X1943900Y238500
X1943517Y223637
X1943217Y221154
X1926100Y231200
X1925835Y233735
X1910340Y220741
X1903032Y228368
X1903020Y225776
X1902907Y231294
X1902909Y223195
X1899816Y235035
X1896529Y235080
X1892274
X1885000Y227500
X1884651Y234975
X1884400Y224100
X1882345Y231837
X1882200Y234400
X1881900Y224100
X1844444Y224035
X1843600Y239000
X1840300Y239300
X1836900Y232700
X1835936Y235604
X1826662Y232191
X1826085Y236034
X1822877Y235852
X1822638Y232106
X1819488
X1810040
X1806083Y232584
X1803280Y232611
X1800591Y232106
X1793700Y232500
X1793600Y235100
X1791141Y232106
X1784440Y232938
X1782452Y237712
X1781693Y232106
X1779451Y237712
X1774451
X1772244Y232106
X1771451Y237712
X1768700Y233644
X1766077Y232681
X1763554Y237712
X1762795Y232106
X1760554Y237712
X1755554
X1753347Y232106
X1752554Y237712
X1749462Y232955
X1744603Y232489
X1742398Y234681
X1739847Y233334
X1736847
X1736400Y237300
X1733900
X1733880Y232810
X1719080Y236152
Y232852
X1684300Y233579
X1681632Y233665
X1681116Y238614
X1643106Y233913
X1640871Y235210
X1632128Y225472
X1628624Y225318
X1626124Y225250
X1621164Y225910
Y223392
X1597201Y238188
X1591865Y237407
X1591174Y225017
X1574560Y237660
X1572700Y239400
X1572730Y235931
X1570318Y238116
X1570272Y234889
X1561104Y234255
X1559577Y236300
X1545802Y233529
X1542690Y236050
X1537972Y236000
X1531935Y224160
X1526150Y234300
X1523580Y237960
X1520413Y239498
X1516549Y234278
X1499559Y231173
X1498685Y224715
X1498478Y233675
X1498022Y221900
X1491438Y221137
X1491265Y226492
X1482004Y222483
X1479700Y224801
X1479500Y238500
X1470950Y229669
X1464150Y235550
X1464200Y231400
X1462700Y221700
X1459548Y221731
X1441750Y236800
X1422281Y221479
X1402400Y223600
X1401565Y229435
X1400066Y236274
X1399978Y233775
X1399600Y223600
X1398600Y228700
X1397400Y237900
Y234959
Y232118
X1397211Y226041
X1394881Y226997
X1391900Y237900
Y234959
Y232118
X1388518Y230789
X1386400Y237900
Y234959
Y232118
X1380900Y237900
Y234959
Y232118
X1375400Y237900
Y235100
Y232118
X1369900Y237900
Y234959
Y232118
X1364400Y237900
Y234959
Y232118
X1358900Y237900
Y234959
Y232118
X1353400Y237900
Y234959
Y232118
X1347900Y237900
Y234959
Y232118
X1342400Y237900
Y234959
Y232118
X1336900Y237900
Y234959
Y232118
X1331400Y237900
Y234959
Y232118
X1325900Y237900
Y234959
Y232118
X1320400Y234959
Y232118
X1320289Y237671
X1315100Y237645
X1314900Y234959
Y232118
X1288800Y233900
X1283720Y223870
X1279950Y229338
X1278183Y231886
X1276628Y234270
X1275154Y236296
X1253791Y226228
X1252221Y228668
X1251395Y226373
X1248672Y226494
X1245300Y224800
X1243300Y223100
X1220017Y220323
X1215700Y223600
X1212199Y239596
Y231797
Y223996
X1208519Y237647
Y233746
Y229847
Y225947
X1205139Y239596
Y231797
Y227896
Y220096
X1201759Y237647
Y233746
Y229847
Y225947
Y222047
X1198379Y239596
Y235696
Y231797
Y227896
Y220096
X1194999Y237647
Y233746
Y225947
Y222047
X1191619Y239596
Y231797
Y227896
Y220096
X1188239Y237647
Y233746
Y229847
Y225947
Y222047
X1184859Y239596
Y235696
Y231797
Y223996
X1181479Y237647
Y233746
Y229847
Y225947
Y222047
X1178099Y235696
Y227896
Y220096
X1174719Y237647
Y233746
Y229847
Y225947
X1171339Y239596
Y235696
Y231797
Y223996
Y220096
X1167960Y237647
Y233746
Y229847
Y225947
Y222047
X1164580Y239596
Y235696
Y227896
Y223996
Y220096
X1161200Y233746
Y229847
Y225947
Y222047
X1157820Y239596
Y235696
Y231797
Y223996
Y220096
X1154440Y233746
Y229847
Y225947
Y222047
X1151060Y239596
Y235696
Y231797
Y227896
Y223996
Y220096
X1147680Y237647
Y233746
Y225947
Y222047
X1144300Y239596
Y235696
Y231797
Y227896
Y223996
X1136420Y237647
Y233746
Y229847
Y225947
Y222047
X1133040Y235696
Y227896
Y223996
X1129660Y237647
Y233746
Y225947
Y222047
X1126280Y239596
Y231797
Y227896
Y223996
X1122900Y237647
Y233746
Y229847
X1119521Y239596
Y231797
Y227896
Y223996
Y220096
X1116141Y237647
Y233746
Y229847
Y222047
X1112761Y239596
Y231797
Y223996
X1109381Y237647
Y233746
Y225947
Y222047
X1106001Y239596
Y231797
Y227896
Y223996
X1102621Y237647
Y233746
Y229847
X1099241Y239596
Y227896
Y223996
Y220096
X1095861Y237647
Y233746
Y229847
Y222047
X1092481Y231797
Y223996
X1089101Y237647
Y233746
Y225947
Y222047
X1085721Y239596
Y231797
Y227896
Y223996
X1082341Y237647
Y233746
Y229847
Y222047
X1078962Y239596
Y227896
Y223996
Y220096
X1075582Y237647
Y233746
Y229847
Y225947
X1072202Y239596
Y231797
Y223996
X1068822Y237647
Y233746
Y229847
X1065242Y239596
Y235696
Y223996
Y220096
X1057314Y232509
Y224709
Y220809
X1049284Y238360
Y226660
Y222760
X1045904Y232509
Y220809
X1042524Y238360
Y226660
X1039145Y232509
Y228610
Y220809
X1035765Y238360
Y226660
X1032385Y232509
Y220809
X1029005Y238360
Y234460
Y226660
X1025625Y232509
Y228610
Y220809
X1022245Y238360
Y226660
X1018865Y232509
Y220809
X1015485Y238360
Y234460
Y226660
Y222760
X1012105Y232509
Y228610
Y220809
X1008725Y238360
Y226660
Y222760
X1005345Y232509
Y228610
Y220809
X1001965Y238360
Y234460
Y226660
Y222760
X998586Y232509
Y220809
X995206Y238360
Y230559
Y226660
X991826Y232509
Y220809
X988446Y238360
Y234460
Y230560
X985066Y236409
Y224709
X981686Y238360
Y234460
X978306Y232509
Y220809
X974926Y238360
Y234460
Y230559
Y226660
Y222760
X971546Y236409
Y232509
Y224709
Y220809
X968166Y238360
Y226660
X964786Y232509
Y224709
Y220809
X961406Y238360
Y230559
Y222760
X958026Y236409
Y232509
Y228610
Y224709
Y220809
X954647Y230559
Y226660
X951267Y236409
Y228610
Y224709
X947887Y238360
Y234460
Y230559
Y226660
X944507Y236409
Y228610
Y224709
Y220809
X941127Y238360
Y234460
Y230559
Y226660
Y222760
X937747Y236409
Y232509
Y224709
Y220809
X934367Y234460
Y230559
Y226660
X930987Y236409
Y232509
Y224709
Y220809
X927607Y234460
Y230559
X924227Y236409
Y232509
Y228610
Y224709
Y220809
X920847Y238360
X913787
Y226660
X913700Y222710
X847600Y238400
X841400Y238300
X790900Y234000
Y229700
X790882Y221723
X790846Y225774
X789576Y223737
X789500Y231800
X789471Y227742
X775171Y234316
X775200Y230500
X775171Y227116
X775232Y223633
Y221133
X766732Y225189
X766632Y222589
X761580Y220160
X760304Y235827
X759700Y232000
X749126Y220843
X742897Y229573
Y226773
X742937Y223774
Y221174
X740437Y224964
Y222364
X740300Y228100
X737837Y224964
Y222364
X736612Y237908
X727997Y239195
X727969Y236770
X722050Y221150
X719315Y239104
X718300Y227400
X713800Y221544
X713700Y224144
X710900Y231660
X710500Y224500
X707653Y226347
X704450Y226600
X701700
X700000Y233700
X694361Y223317
Y220817
X690861Y223317
Y220817
X688643Y225980
X688388Y231280
X678400Y224100
X677400Y232300
X675200Y224100
X674300Y232200
X672500Y224100
X671100Y232200
X669900Y224000
X668100Y232200
X632500Y238500
Y235000
X623648Y226994
Y224494
Y221994
X621148Y229494
Y226994
Y221994
X618648Y229494
Y226994
Y224494
X616148Y226994
Y221994
X613648Y229494
Y226994
Y224494
Y221994
X611148Y229494
Y224494
Y221994
X608648Y226994
Y224494
X606148Y229494
X603300Y226700
X600400Y226800
X592300Y220500
X581102Y220006
X580360Y234590
Y230060
X577832Y233729
X577849Y231119
X572930Y232750
Y228130
X570528Y231543
X570404Y229015
X564084Y235685
X562630Y227896
X562591Y220096
X558911Y229847
Y225947
Y222047
X555531Y231797
Y223996
X552151Y233746
Y229847
Y225947
X548771Y239596
Y235696
Y227896
X545391Y237647
Y233746
Y229847
Y225947
Y222047
X542011Y239596
Y235696
Y227896
Y223996
X538631Y237647
Y229847
Y225947
Y222047
X535251Y239596
Y235696
Y231797
Y227896
Y223996
X531871Y237647
Y229847
Y222047
X528491Y235696
Y231797
Y227896
Y223996
Y220096
X525111Y237647
Y229847
Y222047
X521731Y239596
Y235696
Y231797
Y227896
Y223996
Y220096
X518352Y237647
Y233746
Y229847
Y222047
X514972Y239596
Y235696
Y227896
Y223996
Y220096
X511592Y233746
Y229847
Y225947
Y222047
X508212Y239596
Y235696
Y231797
Y223996
Y220096
X504832Y233746
Y229847
Y225947
X501452Y239596
Y235696
Y231797
Y223996
Y220096
X498072Y237647
Y233746
Y229847
Y225947
Y222047
X494692Y235696
Y227896
Y223996
X486812Y237647
Y233746
Y229847
Y225947
Y222047
X483432Y235696
Y227896
Y223996
X480052Y237647
Y233746
Y229847
X476672Y239596
Y231797
Y227896
Y223996
X473292Y237647
Y233746
Y229847
X469913Y239596
Y231797
Y227896
Y223996
Y220096
X466533Y237647
Y233746
Y229847
Y222047
X463153Y239596
Y231797
Y223996
X459773Y237647
Y233746
Y225947
X456393Y239596
Y231797
Y227896
Y223996
X453013Y237647
Y233746
Y229847
Y222047
X449633Y235696
Y227896
Y223996
Y220096
X446253Y237647
Y233746
Y229847
X442873Y239596
Y231797
Y223996
X439493Y237647
Y233746
X436113Y239596
Y231797
Y223996
X432733Y237647
Y233746
Y229847
X429354Y235696
Y227896
Y223996
Y220096
X425974Y237647
Y233746
Y229847
Y225947
X422594Y239596
Y231797
Y227896
Y223996
Y220096
X419214Y237647
Y233746
Y229847
Y222047
X415634Y239596
Y235696
Y227896
Y223996
Y220096
X407706Y232509
Y228610
Y220809
X399676Y238360
Y234460
Y226660
Y222760
X396296Y232509
Y228610
Y220809
X392916Y238360
Y234460
Y226660
Y222760
X389537Y232509
Y228610
Y220809
X386157Y238360
Y234460
Y226660
Y222760
X382777Y236409
Y232509
Y228610
Y220809
X379397Y238360
Y230559
Y226660
Y222760
X376017Y236409
Y232509
Y228610
Y220809
X372637Y238360
Y234460
Y226660
Y222760
X369257Y232509
Y228610
Y220809
X365877Y238360
Y234460
Y226660
Y222760
X362497Y232509
Y228610
Y220809
X359117Y238360
Y234460
Y226660
Y222760
X355737Y232509
Y228610
Y220809
X352357Y238360
Y234460
Y226660
Y222760
X348978Y232509
Y228610
Y220809
X345598Y238360
Y226660
X342218Y232509
Y228610
Y220809
X338838Y238360
Y234460
Y222760
X335458Y236409
Y224709
X332078Y238360
Y234460
X328698Y232509
Y220809
X325318Y238360
Y234460
Y230559
Y226660
Y222760
X321938Y236409
Y232509
Y228610
Y224709
Y220809
X318558Y238360
Y234460
Y226660
X315178Y236409
Y232509
Y228610
Y224709
Y220809
X311798Y238360
Y230559
Y222760
X308418Y236409
Y232509
Y228610
Y224709
Y220809
X305039Y234460
Y230559
Y226660
X301659Y236409
Y228610
Y224709
Y220809
X298279Y238360
Y234460
Y230559
Y226660
X294899Y236409
Y228610
Y224709
Y220809
X291519Y238360
Y234460
Y230559
Y226660
Y222760
X288139Y236409
Y232509
Y224709
X284759Y238360
Y234460
Y230559
Y226660
Y222760
X281379Y232509
Y228610
Y224709
Y220809
X277999Y238360
Y234460
Y230559
Y222760
X274619Y236409
Y232509
Y228610
Y224709
Y220809
X271239Y238360
X264179
Y226660
X264092Y222710
X197617Y238089
X191537Y237989
X169150Y227600
Y223600
X141263Y234216
X141300Y221700
X141200Y229600
X141211Y225615
X139763Y231700
Y227600
Y223700
X125663Y230716
X125563Y234316
Y227116
X125624Y223633
Y221133
X118008Y220991
X117080Y225330
X116310Y222940
X112904Y237218
X107750Y238730
X99500Y223800
X-18000Y247400
X-15000
X19904Y254162
X57500Y254100
X99758Y240300
X108000Y249330
X115525Y245372
X115497Y248376
X116000Y254643
X117063Y257016
X118008Y252991
X122203Y246675
X122820Y244133
X125563Y250616
X125624Y253133
Y255633
X125563Y259116
X127500Y243500
X128200Y250700
X130324Y244033
X137763Y247216
Y249716
X139631Y251900
X139763Y255700
Y259600
X141263Y247216
Y249716
X141300Y253700
X141313Y257533
X191537Y240489
Y242989
X197617Y240589
Y243089
X206800Y246500
X264179Y246160
Y250060
Y253960
Y257860
X267859Y240309
Y244209
Y252009
Y255909
Y259809
X271239Y246160
Y250060
Y257860
X274619Y240309
Y244209
Y248109
Y252009
Y255909
Y259809
X277999Y242260
Y246160
Y250060
Y253960
X281379Y240309
Y248109
Y252009
Y255909
Y259809
X284759Y242260
Y246160
Y253960
Y257860
X288139Y244209
Y248109
Y252009
Y255909
X291519Y242260
Y246160
Y250060
Y253960
Y257860
X294899Y244209
Y248109
Y255909
X298279Y242260
Y246160
Y250060
Y253960
Y257860
X301659Y240309
Y248109
Y255909
Y259809
X305039Y242260
Y246160
Y250060
Y253960
X308418Y240309
Y244209
Y252009
Y255909
Y259809
X315178Y240309
X318558Y242260
Y246160
Y250060
X321938Y244209
Y248109
Y255909
Y259809
X325318Y242260
Y246160
Y250060
Y253960
Y257860
X328698Y240309
Y248109
Y252009
Y259809
X332078Y242260
Y246160
Y250060
Y253960
Y257860
X335458Y244209
Y248109
Y252009
Y259809
X338838Y242260
Y246160
Y253960
Y257860
X342218Y240309
Y244209
Y255909
Y259809
X345598Y246160
X348978Y240309
Y244209
Y248109
X352357Y246160
X355737Y240309
Y244209
Y248109
Y259809
X359117Y246160
Y257860
X362497Y240309
Y244209
Y255909
Y259809
X365877Y253960
Y257860
X369257Y240309
Y244209
Y252009
Y255909
X372637Y250060
Y253960
X376017Y240309
Y248109
Y252009
X378267Y258400
X379397Y250060
X381647Y256400
X382777Y248109
X385027Y254259
X386157Y250060
X388407Y256500
X389537Y248109
X391787Y254259
X392916Y250060
X395166Y256400
X396296Y248109
X398546Y254259
X399676Y246160
Y250060
X401926Y256500
X405306Y254500
X407706Y240309
Y248109
X415634Y247396
X418084Y253546
X419214Y241547
Y245447
Y249347
X421464Y255497
X422594Y243496
Y251296
X425974Y241547
Y245447
Y249347
X429354Y243496
Y247396
Y251296
X431604Y257446
X432733Y241547
Y245447
Y249347
X434983Y255497
X436113Y243496
Y247396
Y251296
X438363Y257446
X439493Y241547
Y245447
Y249347
Y253247
X441743Y259397
X442873Y243496
Y247396
Y251296
Y255196
X446253Y241547
Y245447
Y249347
Y253247
Y257147
X449633Y243496
Y247396
Y251296
Y255196
Y259096
X453013Y241547
Y245447
Y249347
Y257147
X456393Y243496
Y251296
Y255196
Y259096
X459773Y241547
Y245447
Y249347
Y257147
X463153Y243496
Y251296
Y255196
Y259096
X466533Y245447
Y249347
Y257147
X469913Y243496
Y247396
Y251296
Y255196
Y259096
X473292Y245447
Y249347
Y257147
X476672Y243496
Y251296
Y255196
Y259096
X480052Y241547
Y245447
Y249347
Y257147
X483432Y243496
Y251296
Y255196
Y259096
X486812Y241547
Y245447
Y249347
Y257147
X494692Y243496
Y247396
Y251296
Y255196
X498072Y241547
Y245447
Y249347
X501452Y247396
Y259096
X504832Y241547
Y245447
Y253247
X508212Y247396
X508707Y258532
X511592Y241547
Y245447
Y249347
Y253247
X514972Y243496
Y247396
Y251296
Y255196
X518352Y241547
Y245447
Y249347
Y253247
Y257147
X521731Y243496
Y247396
Y251296
Y255196
Y259096
X525111Y245447
Y253247
Y257147
X528491Y243496
Y247396
Y255196
X531871Y241547
Y249347
Y257147
X535251Y243496
Y247396
Y251296
Y255196
Y259096
X538631Y249347
Y257147
X542011Y247396
Y255196
X545391Y241547
Y253247
X548771Y243496
Y247396
Y251296
Y255196
X552151Y241547
Y245447
Y249347
Y257147
X555531Y247396
Y251296
Y255196
X558911Y241547
Y249347
Y253247
Y257147
X562591Y243496
Y251296
Y255196
X565124Y243496
X567868Y243482
X570400Y243500
X573100Y258600
X575600Y259300
X614456Y244956
X617235Y247735
X618279Y251393
X620850Y253416
X621165Y256075
X624500Y240500
X630200Y248100
X632532Y241717
X632692Y248172
X643100Y253700
X649800Y252600
X651235Y249165
X654950Y253446
X657700Y250172
X659900Y256900
X660588Y250312
X662800Y248600
X667240Y246600
X667600Y250200
X669750Y246350
X672200Y256800
X672530Y246300
X675380Y246340
X677800Y254100
X678000Y246400
X690380Y252240
X700400Y257200
X701800Y246480
X702000Y243900
X704090Y256080
X704500Y252500
X710627Y242061
X710572Y244773
X715200Y258900
X717420Y249920
X719360Y241504
X720450Y249950
X723400Y250000
X725725Y241560
X726328Y249979
X730000Y254675
X731662Y247716
X736625Y240308
X739400Y253400
X739500Y247500
X746321Y240569
X746303Y243122
X748700Y254000
Y257500
X751363Y254207
X754263
X761480Y242720
X765007Y252363
X765144Y245508
X765116Y248512
X766532Y254652
X766632Y257252
X768560Y244055
X771650Y246451
X775171Y250616
X775232Y253133
Y255633
X775171Y259116
X777000Y243500
X777700Y250600
X779932Y244033
X787371Y247216
Y249716
X789432Y252000
Y255800
Y259800
X790871Y247216
Y249716
X790900Y253900
X790867Y257724
X841400Y240800
Y243300
X847600Y240900
Y243400
X913787Y246160
Y250060
Y253960
X917467Y240309
Y244209
Y252009
Y255909
Y259809
X920847Y246160
Y257860
X924227Y240309
Y244209
Y248109
Y252009
Y255909
Y259809
X927607Y242260
Y250060
Y253960
Y257860
X930987Y240309
Y244209
Y252009
Y259809
X934367Y246160
Y253960
Y257860
X937747Y240309
Y248109
Y252009
Y255909
X941127Y242260
Y246160
Y250060
Y253960
Y257860
X944507Y244209
Y248109
Y255909
X947887Y242260
Y246160
Y253960
X951267Y240309
Y248109
Y255909
Y259809
X954647Y242260
Y246160
Y250060
X958026Y240309
Y244209
Y252009
Y255909
Y259809
X964786Y240309
X968166Y242260
Y246160
X971546Y248109
Y255909
Y259809
X974926Y242260
Y250060
Y253960
X978306Y248109
Y252009
Y255909
Y259809
X981686Y242260
Y250060
X985066Y244209
Y248109
Y252009
Y255909
Y259809
X988446Y242260
Y246160
Y250060
Y253960
X991826Y244209
Y248109
Y252009
Y255909
Y259809
X995206Y246160
X998586Y240309
Y244209
Y248109
X1005345Y240309
Y244209
Y248109
Y259809
X1008725Y257860
X1012105Y240309
Y244209
Y255909
Y259809
X1015485Y253960
Y257860
X1018865Y240309
Y244209
Y252009
Y255909
X1022245Y250060
Y253960
X1025625Y240309
Y248109
Y252009
X1027875Y258400
X1029005Y250060
X1031255Y256400
X1032385Y248109
X1034635Y254259
X1035765Y250060
X1038015Y256500
X1039145Y248109
X1041395Y254259
X1042524Y250060
X1044774Y256400
X1045904Y248109
X1048154Y254259
X1049284Y246160
Y250060
X1051534Y256500
X1054914Y254500
X1057314Y240309
Y244209
Y248109
X1065242Y247396
X1067692Y254000
X1068822Y241547
Y245447
Y249347
X1071072Y255728
X1072202Y243496
Y251296
X1075582Y245447
Y249347
X1078962Y247396
Y251296
X1081212Y257600
X1082341Y245447
Y249347
X1084591Y255497
X1085721Y243496
Y247396
Y251296
X1087971Y257800
X1089101Y241547
Y245447
Y249347
Y253247
X1091351Y259600
X1092481Y243496
Y247396
Y251296
Y255196
X1095861Y245447
Y249347
Y253247
Y257147
X1099241Y247396
Y251296
Y255196
Y259096
X1102621Y245447
Y257147
X1106001Y243496
Y247396
Y251296
Y259096
X1109381Y241547
Y245447
Y253247
X1112761Y243496
Y247396
Y251296
Y259096
X1116141Y245447
Y253247
Y257147
X1119521Y247396
Y251296
Y255196
Y259096
X1122900Y245447
Y249347
Y257147
X1126280Y243496
Y251296
Y255196
Y259096
X1129660Y241547
Y245447
Y253247
X1133040Y243496
Y251296
Y259096
X1136420Y241547
Y245447
Y249347
Y257147
X1144300Y243496
Y247396
Y251296
Y255196
X1147680Y245447
Y249347
X1151060Y243496
Y247396
Y259096
X1154440Y241547
Y245447
Y249347
Y253247
Y257147
X1157820Y247396
Y251296
X1159410Y259720
X1161200Y241547
Y245447
Y249347
Y253247
X1164580Y247396
Y251296
Y255196
X1167960Y241547
Y245447
Y249347
Y253247
Y257147
X1171339Y243496
Y247396
Y251296
Y255196
Y259096
X1174719Y249347
Y253247
Y257147
X1178099Y243496
Y247396
Y255196
Y259096
X1181479Y241547
Y249347
Y257147
X1184859Y243496
Y247396
Y251296
Y255196
Y259096
X1188239Y241547
Y249347
Y257147
X1191619Y243496
Y251296
Y255196
Y259096
X1194999Y241547
Y245447
Y249347
Y253247
Y257147
X1198379Y243496
Y247396
Y251296
Y255196
Y259096
X1201759Y241547
Y245447
Y249347
Y257147
X1205139Y251296
Y259096
X1208519Y241547
Y249347
Y257147
X1212199Y243496
Y251296
X1214732Y243496
X1217476Y243482
X1220194Y243384
X1223100Y258600
X1225908Y259300
X1268404Y246304
X1270478Y243490
X1272761Y240220
X1274100Y255300
X1275577Y253123
X1277504Y250346
X1279393Y247602
X1306585Y258250
X1308200Y255800
X1309462Y240229
X1310950Y255650
X1399852Y252353
X1407274Y245652
X1433057Y257388
X1433700Y254200
X1434300Y251600
X1434800Y248900
X1435655Y246550
X1437400Y244150
X1437800Y258300
X1438500Y255400
X1439700Y253100
X1444850Y242730
X1447154Y251710
X1448500Y257700
X1452200Y254500
X1452728Y243306
X1454000Y259700
X1455600Y254826
X1458318Y243000
X1458800Y254882
X1461348Y244350
X1462704Y254470
X1464700Y256100
X1465063Y253544
X1466404Y245350
X1468450Y252900
X1469004Y246287
X1469150Y242931
X1470556Y256900
X1470950Y252846
X1471604Y246287
X1472200Y243000
X1474096Y256706
X1474520Y251740
X1475004Y246287
X1477397Y256657
X1478500Y252000
X1479000Y254500
X1482400Y248000
X1483457Y244568
X1484000Y257500
X1484700Y251800
X1486926Y247834
X1487500Y244500
X1491407Y258353
X1491700Y241661
X1493199Y255507
X1495682Y255861
X1495696Y258361
X1499070Y255934
X1499472Y250370
X1502165Y251200
X1503842Y245678
X1504772Y259229
X1505946Y254432
X1509800Y244676
X1509814Y247215
X1512790Y240099
X1516613Y240656
X1519300Y245196
X1523470Y242580
X1525650Y248700
X1528460Y244371
X1530200Y257200
X1532237Y247801
X1541325Y245090
X1542751Y240477
X1547375Y245850
X1547869Y243356
X1558700Y252000
X1563157Y258164
X1563440Y250955
X1567000Y259560
X1568120Y251710
X1568365Y247761
X1571876Y255800
X1574900Y240900
X1582699Y252646
X1586950Y251267
X1589592Y252472
X1596300Y250320
X1596600Y246350
X1598028Y256422
X1599270Y246310
X1606849Y241210
X1608489Y252095
X1609051Y243415
X1620250Y254741
X1620240Y257660
X1624798Y241937
X1627024Y253387
X1627043Y256900
X1637281Y254322
X1638216Y246021
X1643775Y246137
X1657500Y259700
X1657949Y257240
X1661186Y245352
X1662000Y250008
X1662956Y243582
X1664324Y248002
X1666345Y241987
X1666329Y245139
X1667667Y257920
X1670140Y257547
X1670822Y254691
X1680769Y242605
X1681760Y245500
X1683615Y250493
X1683729Y242346
X1684509Y245631
X1686113Y250604
X1688451Y249716
X1690565Y251052
X1715078Y250231
X1715837Y246178
X1718820Y249032
X1720651Y246141
X1722251Y250532
X1724181Y246159
X1724944Y250324
X1727444
X1727896Y246175
X1729944Y250324
X1746900Y249804
X1751900Y249700
X1763300Y250100
X1768516Y249983
X1771243Y250100
X1790383Y250498
X1793384
X1798384
X1801384
X1804388Y249904
X1809281Y250498
X1812282
X1817282
X1820281
X1824300Y251800
X1826287Y250000
X1828936Y249900
X1831700Y252272
X1840149Y244425
X1843449
X1843700Y253400
X1846517Y253500
X1850220
X1852300Y252000
X1854374Y248790
X1854720Y253700
X1858400Y251200
X1858420Y253700
X1861605Y253925
X1864305Y253825
X1925600Y242700
X1934750Y240300
Y242700
X1943800Y241800
X1872323Y264167
X1679100Y278924
Y276400
Y273900
Y271300
X1666968Y260611
X1657567Y264600
X1657498Y279900
Y277300
Y274700
Y269700
Y267100
X1637269Y264421
X1637281Y260922
X1636914Y270900
X1636684Y279815
Y277315
Y274815
X1627177Y260267
X1626291Y273309
X1623447Y273273
X1622000Y279495
X1617498Y273433
X1610290Y265352
X1604222Y268107
X1601870Y270470
X1600810Y266006
X1600552Y261281
X1579867Y265445
X1547000Y269400
Y263500
X1544000Y266500
X1541000Y269500
Y263500
X1533596Y273504
X1527657Y278700
X1521962Y278650
X1507003Y272249
X1504461Y274426
X1499681Y279910
X1497082Y277987
X1496812Y273718
X1492753Y273724
X1492697Y267303
X1467040Y260357
X1466006Y265300
X1454350Y262200
X1454056Y266169
X1451850Y262200
X1433362Y278244
X1430365Y262624
X1426905Y267045
X1426658Y274252
X1412579Y268273
X1410979Y270473
X1383753Y265548
X1381031Y265600
X1377522
X1374864Y265629
X1369100Y265500
X1366312Y265525
X1362803
X1359100Y265600
X1356268Y265695
X1352468
X1349500Y265500
X1347468Y268095
X1345050Y272350
X1343668Y268095
X1340866Y268795
X1340248Y271755
X1336448
X1334113Y273115
X1333680Y276035
X1330171
X1330039Y279618
X1327625Y275971
X1327243Y279663
X1323734
X1300444Y267919
X1225908Y261800
X1223508Y262600
X1217200Y270500
X1216234Y268055
Y265555
X1213808Y264800
X1212199Y274696
X1208519Y272747
Y268847
Y264947
X1205139Y274696
Y266896
X1201759Y276646
Y272747
Y268847
Y264947
Y261047
X1198379Y278596
Y270796
Y262996
X1194999Y276646
Y272747
Y268847
Y264947
X1191619Y278596
Y274696
Y270796
Y266896
Y262996
X1188239Y276646
Y272747
Y264947
Y261047
X1184859Y278596
Y274696
Y270796
Y262996
X1181479Y276646
Y272747
Y268847
Y264947
Y261047
X1178099Y278596
Y274696
Y270796
X1174719Y276646
Y272747
Y268847
Y261047
X1171339Y274696
Y266896
X1167960Y276646
Y272747
Y264947
Y261047
X1164580Y278596
Y270796
X1162300Y264947
X1161200Y272747
Y268847
X1159578Y265117
X1159390Y262460
X1157820Y278596
Y270796
Y266896
X1154440Y264947
Y261047
X1151060Y278596
Y274696
Y266896
X1147680Y268847
Y264947
X1144300Y278596
Y274696
Y270796
Y266896
Y262996
X1140920Y268847
Y264947
X1137540Y278596
Y274696
Y270796
Y266896
X1134160Y276646
Y268847
X1130780Y278596
Y274696
X1129660Y264947
Y261047
X1127400Y276646
X1126280Y266896
Y262996
X1122900Y268847
Y264947
Y261047
X1119521Y278596
Y270796
Y266896
Y262996
X1118391Y274997
X1116141Y268847
Y264947
Y261047
X1112761Y262996
X1111631Y271300
X1110648Y276899
X1109381Y261047
X1108125Y276799
X1107561Y269038
X1106001Y262996
X1104871Y267300
X1102621Y261047
X1102336Y274819
X1101491Y265400
X1100200Y273300
X1099186Y278938
X1098111Y263400
X1096756Y278941
X1095700Y268790
X1094731Y261500
X1092300Y267200
X1092100Y264500
X1089100
X1089000Y267000
X1079859Y265000
X1050002Y264899
X1047002
X1043502
X1040502
X1024495Y260300
X1021115Y262300
X1017735Y264300
X1014355Y266300
X1011100Y268100
X1009256Y269777
X1008725Y261760
X1006665Y277360
Y273460
X1006700Y270700
X1005345Y263709
X1001965Y265660
Y261760
X998586Y279310
Y275409
Y271509
Y267609
Y263709
X995206Y277360
Y273460
Y269560
Y265660
X991826Y279310
Y275409
Y271509
Y267609
Y263709
X988446Y265660
Y261760
X985066Y267609
X981686Y269560
Y261760
X978306Y267609
X974926Y273460
Y269560
Y265660
X971546Y275409
Y267609
Y263709
X968166Y277360
Y269560
X964786Y279310
Y271509
Y267609
X961406Y277360
Y273460
Y269560
Y261760
X958026Y279310
Y275409
Y267609
Y263709
X954647Y277360
Y273460
Y269560
Y265660
X951267Y279310
Y275409
Y267609
X947887Y277360
Y265660
Y261760
X944507Y279310
Y275409
Y263709
X941127Y277360
Y269560
Y265660
Y261760
X937747Y279310
Y275409
Y271509
Y263709
X934367Y277360
Y273460
Y265660
X930987Y279310
Y275409
Y271509
Y267609
X927607Y277360
Y269560
Y265660
X924227Y279310
Y275409
Y267609
Y263709
X920847Y277360
Y273460
Y269560
Y265660
X917467Y263709
X916967Y279310
X917000Y276000
X913787Y273460
Y265660
Y261760
X847600Y268200
X845100
X842600
X790871Y279216
Y266216
X790885Y261711
X789500Y263900
X787371Y279216
X779400Y276200
X776700Y275500
X775271Y262716
X775171Y266316
X771650Y278451
X769019Y276400
X765144Y277508
X762616Y270113
X754846Y276340
X754758Y273356
X749100Y279500
X749090Y270250
X748990Y267450
X731100Y279300
Y269300
X725500Y279300
X725300Y269400
X719900Y269300
X719600Y279400
X710675Y263425
X710700Y260200
X709949Y272647
X709700Y275500
X709600Y278100
X706800
X700900Y264100
X700800Y261300
X697255Y267098
X693530Y261240
X690939Y266630
X690704Y271324
X690660Y264000
X690130Y277380
X689960Y260500
X679300Y261700
X678454Y278000
X672300Y269200
X667700Y275600
X662786Y278084
X660901Y279856
X659900Y269200
X656100Y275500
X652700Y270600
X652500Y273600
X647469Y277639
X643591Y266983
X643500Y274868
Y272262
X642855Y269660
X642800Y264000
Y261100
X639320Y268000
X633410Y274610
Y269610
X633308Y263808
X575600Y261800
X573200Y262600
X566926Y268055
Y265555
X564500Y268800
Y264800
X563800Y275900
X558911Y272747
Y268847
Y264947
X555531Y278596
Y274696
Y266896
Y262996
X552151Y276646
Y272747
Y268847
Y261047
X548771Y278596
Y270796
Y266896
Y262996
X545391Y276646
Y272747
Y268847
Y264947
Y261047
X542011Y274696
Y270796
Y266896
X538631Y261047
X535251Y278596
Y270796
Y266896
X531871Y276646
Y268847
Y264947
Y261047
X528491Y278596
Y274696
Y270796
Y262996
X525111Y276646
Y272747
Y268847
Y261047
X521731Y274696
Y266896
X518352Y272747
Y264947
Y261047
X514972Y278596
Y274696
Y270796
X513857Y260881
X511592Y268847
X510401Y260511
X508212Y278596
Y274696
Y270796
Y266896
X504832Y268847
Y264947
Y261047
X501452Y278596
Y274696
Y266896
X498072Y268847
Y264947
X494692Y278596
Y274696
Y270796
Y262996
X491312Y268847
Y264947
X487932Y278596
Y274696
Y270796
Y266896
X484552Y272747
Y268847
X481172Y278596
Y274696
Y270796
X480052Y264947
Y261047
X477792Y276646
Y272747
X476672Y266896
X474413Y274696
X473292Y268847
Y264947
Y261047
X469913Y278596
Y270796
Y262996
X468783Y274997
X466533Y268847
Y264947
Y261047
X463153Y262996
X462023Y271097
X459773Y264947
Y261047
X458643Y269146
X458408Y278940
X458400Y276400
X456393Y262996
X455263Y267197
X453400Y275600
X453013Y261047
X451883Y265246
X450800Y275600
X449848Y278841
X448900Y269600
X448503Y263297
X447148Y278841
X445123Y261346
X444408Y267305
X440500Y266500
X429781Y264793
X400394Y264899
X397394
X393894
X390894
X374887Y260300
X371507Y262300
X368127Y264300
X364747Y266300
X361492Y268100
X359648Y269777
X359117Y261760
X357057Y277360
Y273460
X357092Y270700
X355737Y263709
X352357Y265660
Y261760
X348978Y279310
Y275409
Y271509
Y267609
Y263709
X345598Y277360
Y273460
Y269560
Y265660
X342218Y279310
Y275409
Y271509
Y267609
Y263709
X338838Y265660
X335458Y267609
Y263709
X332078Y269560
Y265660
X328698Y267609
Y263709
X325318Y273460
Y269560
Y265660
X321938Y275409
Y267609
Y263709
X318558Y277360
Y273460
Y269560
X315178Y279310
Y275409
Y267609
Y263709
X311798Y277360
Y273460
Y269560
Y261760
X308418Y279310
Y275409
Y267609
Y263709
X305039Y277360
Y273460
Y269560
Y265660
Y261760
X301659Y279310
Y275409
Y267609
X298279Y277360
Y265660
Y261760
X294899Y279310
Y275409
Y263709
X291519Y277360
Y269560
Y265660
Y261760
X288139Y279310
Y275409
Y271509
Y263709
X284759Y277360
Y273460
Y269560
Y265660
Y261760
X281379Y279310
Y275409
Y271509
Y267609
Y263709
X277999Y277360
Y269560
Y261760
X274619Y279310
Y275409
Y267609
Y263709
X271239Y277360
Y273460
Y269560
Y265660
X267859Y271509
Y263709
X267359Y279310
X267392Y276000
X264179Y273460
Y265660
X239778Y274478
X197037Y270750
X194537
X192037
X141263Y279216
Y266216
X141200Y261600
X139800Y263700
X137763Y279216
X130324Y276033
X127500Y275500
X125663Y262716
X125563Y266316
X123074Y275948
X122400Y278671
X115536Y277508
X113100Y269163
X97200Y265000
X91600Y278700
X84000Y272500
X83300Y267400
X79300Y272300
X62000Y278000
X59500
X53400Y277582
Y274500
X44310Y268160
X41000Y274647
Y265350
X37000Y275000
Y265350
X33490Y267900
X5120Y276058
X2269Y273532
X-15000Y262700
X-18000
X1500Y295000
X7995Y285385
X48800Y282600
Y285100
Y289600
Y292400
X53400Y298100
X58600Y297200
X58700Y283000
Y299800
X61625Y283201
X61900Y286200
X66000Y292700
X66300Y285850
X68300Y281600
X70900
X71500Y298000
X72904Y284898
X76800Y298000
X76900Y292600
X77103Y283900
X82050Y283951
X84300Y289000
Y299000
X84866Y294213
X93400Y296000
X93500Y285000
Y289000
X102322Y295478
X110180Y280920
X115508Y280512
X116000Y286643
X117063Y289016
X118008Y284991
X118800Y298400
X125563Y282616
X125624Y285133
Y287633
X125563Y291116
Y298316
X125663Y294716
X128200Y282600
X137763Y281716
X139730Y284200
X139763Y288200
Y292000
Y296000
X141200Y286100
X141263Y281716
X141261Y290076
X141300Y294000
X141263Y298216
X192037Y299750
X194537
X197037
X203947Y280933
X267359Y283209
X270892Y285500
Y289060
Y292959
Y296860
X271239Y281260
X274619Y283209
Y287109
Y291009
Y294909
Y298809
X277999Y281260
Y285160
Y289060
Y292959
Y296860
X281379Y283209
Y287109
Y291009
Y294909
Y298809
X284759Y281260
Y285160
Y289060
Y292959
Y296860
X288139Y283209
Y287109
Y291009
Y294909
Y298809
X291519Y281260
Y285160
Y289060
Y292959
Y296860
X294899Y283209
Y287109
Y291009
Y294909
Y298809
X298279Y281260
Y285160
Y289060
Y292959
Y296860
X301659Y283209
Y287109
Y291009
Y294909
Y298809
X305039Y281260
Y285160
Y289060
Y292959
Y296860
X308418Y283209
Y287109
Y291009
Y294909
Y298809
X311798Y281260
Y285160
Y289060
Y292959
Y296860
X315178Y283209
Y287109
Y291009
Y294909
Y298809
X318558Y281260
Y285160
Y289060
Y292959
Y296860
X321938Y283209
Y287109
Y291009
Y294909
Y298809
X325318Y281260
Y285160
Y289060
Y292959
Y296860
X328698Y283209
Y287109
Y291009
Y294909
Y298809
X332078Y281260
Y285160
Y289060
Y292959
Y296860
X335458Y283209
Y287109
Y291009
Y294909
Y298809
X338838Y281260
Y285160
Y289060
Y292959
Y296860
X342218Y283209
Y287109
Y291009
Y294909
Y298809
X345598Y281260
Y285160
Y289060
Y292959
Y296860
X348978Y283209
Y287109
Y291009
Y294909
Y298809
X357057Y281260
Y285160
Y289060
Y292959
Y296860
X411294Y292904
X414294
X418494
X421494
X425694
X428694
X432894
X435894
X440094
X443094
X453400Y293686
X463800Y289500
X464000Y294500
X465100Y280300
X469913Y282496
Y286396
Y290296
Y294196
Y298096
X477792Y280547
Y284447
Y288347
Y292247
Y296147
X481172Y282496
Y290296
Y294196
Y298096
X484552Y280547
Y284447
Y288347
Y292245
Y296147
X487932Y282496
Y286396
Y290296
X491312Y292245
X494692Y286396
Y294196
X498072Y296147
X501452Y282496
Y290296
Y294196
Y298096
X504832Y296147
X508212Y290296
Y294196
Y298096
X511592Y284447
Y288347
Y296147
X514972Y286396
Y290296
Y294196
Y298096
X518352Y288347
Y292245
Y296147
X521731Y286396
Y290296
Y294196
Y298096
X525111Y280547
Y284447
Y288347
Y292245
Y296147
X528491Y286396
Y290296
Y294196
Y298096
X531871Y284447
Y288347
Y292245
X535251Y290296
Y294196
X538631Y280547
Y284447
Y288347
Y292245
X542011Y286396
Y294196
Y298096
X545391Y280547
Y284447
Y288347
Y292245
Y296147
X548771Y282496
Y286396
Y290296
Y294196
X552151Y284447
Y288347
Y296147
X555531Y282496
X555831Y294196
Y298096
X558145Y286727
X559211Y280547
X560884Y286396
X627529Y280441
X628525Y287832
X628950Y293550
X631250Y289650
X632869Y293720
X634407Y287915
X636799Y285670
X636985Y288264
X639045Y299555
X639622Y290210
X641665Y281139
X643823Y289650
X644800Y292150
X646520Y297400
X647487Y280308
X652000Y284500
X652100Y288300
X654500Y298600
X654600Y296000
X655000Y284600
X656042Y287439
X657950Y296850
X658500Y284500
X658853Y294305
X661232Y287321
X662200Y284800
X662238Y296146
X663200Y298600
X664267Y292668
X665000Y284800
X668000Y298400
X670800Y292600
Y298400
X672150Y288350
X673922Y298078
X674469Y287375
X680000Y281900
X683490Y282110
X686140Y298260
X686470Y282220
X688924Y288147
X690048Y281053
Y284053
X695000Y289500
X696088Y297069
X704175Y287275
X704214Y290775
X704500Y293800
X706800Y281900
X710272Y281911
X718200Y295000
X724000Y291700
X729405Y290725
X737750Y298894
X741250Y298856
X749800Y282300
X765007Y284363
X764980Y287980
X765116Y280512
X767310Y286530
X775171Y282616
X775232Y285133
Y287633
X775171Y291116
Y298316
X775271Y294716
X777700Y282600
X787371Y281716
X789432Y284200
Y288300
Y292400
X789400Y296200
X790871Y281716
X790900Y286200
Y290300
X790937Y294270
X790871Y298216
X842600Y299900
X845100
X847600
X920500Y285500
Y289060
Y292959
Y296860
X920847Y281260
X924227Y283209
Y287109
Y291009
Y298809
X927607Y281260
Y285160
Y289060
Y292959
Y296860
X930987Y283209
Y287109
Y291009
Y294909
Y298809
X934367Y281260
Y285160
Y289060
Y292959
Y296860
X937747Y283209
Y287109
Y291009
Y294909
Y298809
X941127Y281260
Y285160
Y289060
Y292959
Y296860
X944507Y283209
Y287109
Y291009
Y294909
Y298809
X947887Y281260
Y285160
Y289060
Y292959
Y296860
X951267Y283209
Y287109
Y291009
Y294909
Y298809
X954647Y281260
Y285160
Y289060
Y292959
Y296860
X958026Y283209
Y287109
Y291009
Y294909
Y298809
X961406Y281260
Y285160
Y289060
Y292959
Y296860
X964786Y283209
Y287109
Y291009
Y294909
Y298809
X968166Y281260
Y285160
Y289060
Y292959
Y296860
X971546Y283209
Y287109
Y291009
Y294909
Y298809
X974926Y281260
Y285160
Y289060
Y292959
Y296860
X978306Y283209
Y287109
Y291009
Y294909
Y298809
X981686Y281260
Y285160
Y289060
Y292959
Y296860
X985066Y283209
Y287109
Y291009
Y294909
Y298809
X988446Y281260
Y285160
Y289060
Y292959
Y296860
X991826Y283209
Y287109
Y291009
Y294909
Y298809
X995206Y281260
Y285160
Y289060
Y292959
Y296860
X998586Y283209
Y287109
Y291009
Y294909
Y298809
X1006665Y281260
Y285160
Y289060
Y292959
Y296860
X1060902Y292904
X1063902
X1068102
X1071102
X1075302
X1078302
X1082502
X1085502
X1089702
X1092702
X1113132Y291702
X1113900Y297800
X1116999Y286826
X1119521Y282496
Y286396
Y290296
Y294196
Y298096
X1127400Y280547
Y284447
Y288347
Y292247
Y296147
X1130780Y282496
Y286396
Y290296
Y294196
Y298096
X1134160Y280547
Y284447
Y288347
Y292247
Y296147
X1137540Y282496
Y290296
Y294196
Y298096
X1140920Y292247
Y296147
X1144300Y286396
Y294196
Y298096
X1147680Y280547
Y296147
X1151060Y282496
Y290296
Y294196
Y298096
X1154440Y296147
X1157820Y290296
Y294196
Y298096
X1161200Y284447
Y296147
X1164580Y286396
Y290296
Y294196
Y298096
X1167960Y288347
Y292247
Y296147
X1171339Y286396
Y290296
Y294196
Y298096
X1174719Y280547
Y284447
Y288347
Y292247
Y296147
X1178099Y282496
Y286396
Y290296
Y294196
Y298096
X1181479Y284447
Y288347
Y292247
X1184859Y282496
Y286396
Y290296
Y294196
X1188239Y280547
Y284447
Y288347
Y292247
X1191619Y282496
Y286396
Y290296
Y294196
Y298096
X1194999Y280547
Y284447
Y288347
Y292247
Y296147
X1198379Y282496
Y286396
Y290296
Y294196
X1201759Y280547
Y284447
Y288347
X1205139Y282496
X1205439Y286596
Y290296
Y294196
Y298096
X1208819Y280547
X1299700Y298557
X1302768Y296942
X1303866Y292345
X1305558Y294313
X1306290Y298255
X1308887Y285015
X1314490Y283862
X1314792Y286427
X1316300Y282000
X1318751Y282730
X1319297Y296878
X1319888Y290205
X1321600Y294700
X1322260Y282730
X1323688Y290205
X1325300Y282600
X1334400Y292050
X1335400Y284900
X1337200Y292012
X1338700Y284700
X1345700Y285300
X1347892Y299741
X1352400Y285000
X1353672Y299605
X1355800Y285000
X1359000Y284900
X1365246Y285931
X1368200Y284000
X1381431Y284259
X1398347Y284023
X1398926Y281582
X1402092Y284022
X1404286Y281729
X1405392Y284022
X1433362Y280744
X1493290Y287984
X1493268Y293943
X1493700Y281476
X1496600Y281400
X1496628Y288440
X1496900Y293900
X1499987Y288487
X1501550Y293750
X1508650Y287500
X1511900
X1512182Y293317
X1512300Y280847
X1514722Y293257
X1515482Y280800
X1518006Y286706
X1526722Y295400
X1526900Y292866
X1530500Y287700
X1533838Y288706
X1533914Y286073
X1534400Y296029
X1537500Y292800
X1546612Y287812
X1548199Y285830
X1550800Y296200
X1552900Y281700
X1554800Y290600
X1554775Y295328
X1559500Y290300
X1559800Y285300
X1565000Y290500
X1571293Y284755
X1572336Y287063
X1573790Y284895
X1578577Y284799
X1578630Y293430
X1578790Y290920
X1581077Y284825
X1581940Y295820
X1584568Y281339
X1625846Y286154
X1631300Y280400
X1636684Y283141
X1636800Y287956
X1636822Y292446
Y294946
X1636925Y297444
X1657498Y284900
X1657500Y287800
X1657494Y292816
X1679100Y281593
Y284093
Y286593
Y289500
Y292000
Y294500
Y297000
Y299500
Y304700
Y302100
X1664453Y308557
X1657600Y304500
X1652991Y318741
X1639413Y312735
Y310235
X1639040Y316343
X1638086Y319664
X1636861Y305091
X1636922Y302588
X1590212Y315425
X1587800Y308200
X1585479Y316610
X1583500Y303120
Y300560
X1582800Y312100
X1581834Y318591
X1577486Y307621
X1569926Y308064
X1568524Y312885
X1566910Y315117
X1565235Y303734
X1565244Y300934
X1564411Y315210
X1564427Y311083
X1564400Y308383
X1560400Y307683
X1559997Y310317
X1557250Y315410
X1551404Y309376
X1550619Y303087
X1549000Y316600
X1548273Y313227
X1547882Y318942
X1543864Y311399
X1538450Y314300
X1538206Y303741
X1536027Y305048
X1534833Y309798
X1532850Y303950
X1529734Y319714
X1528250Y311900
X1526936Y307015
X1525677Y311835
X1523935Y318901
X1518060Y317520
X1516301Y313244
X1516138Y310749
X1514067Y315626
X1508455Y313041
X1505923Y309510
X1505935Y306674
X1503538Y318068
X1500840Y319870
X1499723Y300106
X1497179Y306372
X1419343Y310652
X1419333Y307598
X1419283Y304570
X1419220Y301983
X1413983Y304645
X1413943Y310628
X1413720Y307634
Y301983
X1413387Y316233
X1410800Y316100
X1408760Y304637
X1408580Y310632
X1408537Y307630
Y302046
X1403260Y310623
X1403300Y304640
X1403037Y307630
Y302046
X1400558Y316357
X1398062Y315743
X1397880Y304640
X1397640Y310631
X1397635Y307630
Y302051
X1392380Y304640
X1392340Y310625
X1392226Y319458
Y315658
X1392135Y307630
Y302051
X1389600Y315200
X1386265Y304310
X1386101Y301465
X1386048Y310310
Y307310
X1383639Y315274
X1381100Y304360
X1380904Y319747
Y315947
X1380910Y310300
X1380601Y301465
X1380548Y307310
X1375040Y304135
X1374900Y310130
X1374840Y307130
X1374820Y301219
X1371090Y319195
Y315395
X1369540Y310125
Y304135
X1369340Y307130
X1369320Y301219
X1368947Y313993
X1364213Y303694
X1364044Y309691
Y306690
X1364014Y300815
X1363059Y314514
X1360294Y318825
Y315025
X1358792Y309760
X1358800Y303700
X1358544Y306690
X1358514Y300815
X1357452Y319395
X1353359Y303767
X1353142Y309761
Y306760
X1350650Y315050
X1349134Y317436
X1348190Y303810
X1348080Y309825
X1347642Y306760
X1342500Y312100
X1342480Y303852
X1341920Y309755
X1341740Y306760
Y301243
X1341375Y319675
Y314675
X1338500Y319600
X1336793Y303784
X1336480Y309755
X1336240Y306760
Y301243
X1331650Y317250
X1323750Y319750
X1319310Y300795
X1316600Y305500
X1305950Y306611
X1305873Y309245
X1303380Y309441
X1302203Y314439
X1299735Y301298
X1208826Y319544
X1205500Y309797
X1205439Y305896
X1198379Y313696
Y309797
X1194999Y319547
Y315647
Y307847
Y303947
Y300047
X1191619Y317596
Y309797
Y305896
Y301996
X1188239Y319547
Y315647
Y311747
Y303947
X1184859Y317596
Y313696
Y309797
Y301996
X1181479Y319547
Y311747
Y307847
Y303947
Y300047
X1178099Y317596
Y313696
Y309797
Y305896
Y301996
X1174719Y315647
Y311747
Y307847
Y303947
Y300047
X1171339Y317596
Y313696
Y309797
Y305896
Y301996
X1167960Y319547
Y315647
Y311747
Y307847
Y303947
Y300047
X1164580Y317596
Y313696
Y309797
Y305896
Y301996
X1161200Y319547
Y315647
Y311747
Y307847
Y303947
Y300047
X1157820Y317596
Y313696
Y305896
Y301996
X1154440Y319547
Y315647
Y311747
Y307847
Y303947
Y300047
X1151060Y317596
Y313696
Y309797
Y305896
Y301996
X1147680Y319547
Y315647
Y311747
Y307847
Y303947
Y300047
X1144300Y317596
Y313696
Y309797
Y305896
Y301996
X1140920Y319547
Y311747
Y307847
Y303947
Y300047
X1137540Y317596
Y309797
Y305896
X1134160Y315647
Y311747
Y307847
Y300047
X1130780Y313696
Y309797
Y305896
Y301996
X1127400Y319547
Y315647
Y311747
Y307847
Y303947
Y300047
X1119521Y317596
Y313696
Y309797
Y305896
Y301996
X1103756Y310341
Y307841
X1101256Y308841
X1098756Y309841
X1095702Y309904
X1092756Y309841
X1089702Y309904
X1085502
X1082502
X1078302
X1075302
X1071102
X1068102
X1063902
X1060902
X1028039Y312414
X1025438Y312381
X1022915Y312372
X1020404Y312408
X1017957Y312421
X1006665Y316360
Y312460
Y308560
Y304660
Y300760
X998586Y318309
Y314409
Y310509
Y306609
Y302709
X995206Y316360
Y312460
Y308560
Y304660
Y300760
X991826Y318309
Y314409
Y310509
Y306609
Y302709
X988446Y316360
Y312460
Y308560
Y304660
Y300760
X985066Y318309
Y314409
Y310509
Y306609
Y302709
X981686Y316360
Y312460
Y308560
Y304660
Y300760
X978306Y318309
Y314409
Y310509
Y306609
Y302709
X974926Y316360
Y312460
Y308560
Y304660
Y300760
X971546Y318309
Y314409
Y310509
Y306609
Y302709
X968166Y316360
Y312460
Y308560
Y304660
Y300760
X964786Y318309
Y314409
Y310509
Y306609
Y302709
X961406Y316360
Y312460
Y308560
Y304660
Y300760
X958026Y318309
Y314409
Y310509
Y306609
Y302709
X954647Y316360
Y312460
Y308560
Y304660
Y300760
X951267Y318309
Y314409
Y310509
Y306609
Y302709
X947887Y316360
Y312460
Y308560
Y304660
Y300760
X944507Y318309
Y314409
Y310509
Y306609
Y302709
X941127Y316360
Y312460
Y308560
Y304660
Y300760
X937747Y318309
Y314409
Y310509
Y306609
Y302709
X934367Y316360
Y312460
Y308560
Y304660
Y300760
X930987Y318309
Y314409
Y310509
Y306609
Y302709
X927607Y316360
Y312460
Y308560
Y304660
Y300760
X924227Y318309
Y314409
Y310509
Y306609
Y302709
X920547Y316160
X920500Y311960
Y308560
Y304660
Y300760
X917167Y318309
X790871Y313716
Y311216
X790800Y317700
X789478Y315671
X789432Y319900
X787371Y313716
Y311216
X779100Y307900
X777800Y314700
X776270Y307100
X775232Y319633
Y317133
X775171Y314616
X771600Y310600
X771278Y307918
X767000Y318500
X765116Y312512
X765144Y309508
X765007Y316363
X762842Y302434
X756114Y316209
X743600Y304100
X741512Y315538
X737912Y315500
X736000Y303400
X727300Y302910
X713970Y310860
Y308360
X707130Y310150
X706300Y318400
X705800Y301600
X704404Y315875
Y310875
X697120Y305349
Y300349
X695800Y308000
X695400Y318000
X688100Y308600
X687400Y319833
X687138Y317397
X678200Y319300
Y313700
Y307800
X672700Y307700
X667100
X660700
X656300Y312300
X655900Y316500
Y307700
X646900Y317300
X646700Y308850
X639100Y319500
Y309500
X637561Y317000
Y312000
X637600Y307000
Y302000
X561971Y317320
X559211Y319547
X555831Y309797
Y305896
X548771Y313696
Y309797
X545391Y319547
Y315647
Y307847
Y303947
Y300047
X538631Y319547
Y311747
X535251Y309797
Y301996
X531871Y319547
Y311747
Y307847
Y303947
Y300047
X528491Y317596
Y313696
Y309797
Y301996
X525111Y311747
Y307847
Y303947
Y300047
X521731Y317596
Y313696
Y309797
Y305896
Y301996
X518352Y319547
Y315647
Y307847
Y303947
Y300047
X514972Y317596
Y313696
Y309797
Y305896
Y301996
X511592Y319547
Y315647
Y307847
Y300047
X508212Y317596
Y313696
Y309797
Y305896
Y301996
X504832Y319547
Y315647
Y311747
Y303947
Y300045
X501452Y317596
Y313696
Y301996
X498072Y319547
Y315647
Y311747
Y303947
Y300047
X494692Y317596
Y313696
Y309797
Y305896
X491312Y319547
Y311747
Y307847
Y300047
X487932Y317596
Y309797
X484552Y315647
Y307847
Y300047
X481172Y313696
Y309797
Y305896
Y301996
X477792Y319547
Y315647
Y311747
Y307851
Y303947
Y300047
X469913Y317596
Y313696
Y309797
Y305896
Y301996
X463671Y319386
X462948Y315251
X462848Y312741
X454148Y310341
Y307841
X451648Y308341
X449500Y309800
X447000
X443148Y309841
X440094
X435894Y309904
X432894
X428694
X425694
X421494
X418494
X414294
X411294
X378156Y312441
X375674
X373162Y312400
X370650Y312441
X368165Y312504
X357057Y316360
Y312460
Y308560
Y304660
Y300760
X348978Y318309
Y314409
Y310509
Y306609
Y302709
X345598Y316360
Y312460
Y308560
Y304660
Y300760
X342218Y318309
Y314409
Y310509
Y306609
Y302709
X338838Y316360
Y312460
Y308560
Y304660
Y300760
X335458Y318309
Y314409
Y310509
Y306609
Y302709
X332078Y316360
Y312460
Y308560
Y304660
Y300760
X328698Y318309
Y314409
Y310509
Y306609
Y302709
X325318Y316360
Y312460
Y308560
Y304660
Y300760
X321938Y318309
Y314409
Y310509
Y306609
Y302709
X318558Y316360
Y312460
Y308560
Y304660
Y300760
X315178Y318309
Y314409
Y310509
Y306609
Y302709
X311798Y316360
Y312460
Y308560
Y304660
Y300760
X308418Y318309
Y314409
Y310509
Y306609
Y302709
X305039Y316360
Y312460
Y308560
Y304660
Y300760
X301659Y318309
Y314409
Y310509
Y306609
Y302709
X298279Y316360
Y312460
Y308560
Y304660
Y300760
X294899Y318309
Y314409
Y310509
Y306609
Y302709
X291519Y316360
Y312460
Y308560
Y304660
Y300760
X288139Y318309
Y314409
Y310509
Y306609
Y302709
X284759Y316360
Y312460
Y308560
Y304660
Y300760
X281379Y318309
Y314409
Y310509
Y306609
Y302709
X277999Y316360
Y312460
Y308560
Y304660
Y300760
X274619Y318309
Y314409
Y310509
Y306609
Y302709
X270939Y316160
X270892Y311960
Y308560
Y304660
Y300760
X267359Y318309
X141300Y317500
X141263Y313716
Y311216
X139763Y319400
X139582Y315800
X137763Y313716
Y311216
X130324Y308033
X128200Y314800
X127500Y307500
X125624Y319633
Y317133
X125563Y314616
X123301Y308044
X122493Y310633
X118008Y316991
X116000Y318643
X115508Y312512
X115536Y309508
X113000Y304000
X109960Y313190
X104600Y316602
X103500Y308500
Y304700
Y302100
X88600Y302997
X84300Y310700
Y305700
X84000Y316083
X81324Y316119
X77500Y312500
X77300Y315600
X76800Y303400
X75626Y310418
X72600Y310800
X69125Y310625
X66500Y303400
X64700Y310525
X64000Y316500
Y313900
X58600Y302700
X58400Y314600
X53500Y307300
X53250Y302800
X53100Y315000
X48550Y301650
X6806Y302347
X3806
X47100Y327000
X52804Y333247
X53000Y323500
X53025Y337475
X53100Y327000
X56300Y338500
X59452Y338800
X61300Y328600
X62900Y339000
X65800Y338900
X66900Y322000
X68418Y336150
X69000Y338800
X69500Y322000
X70700Y330349
X72000Y338800
X72100Y321800
X74800Y338850
X74887Y321780
X77600Y320800
X79400Y325400
X79410Y331636
X79600Y335200
X82150Y335800
X84000Y324542
X85300Y335750
X87400Y337200
X88840Y324740
X92086Y324258
X94360Y335210
X94938Y323467
X98680Y338080
X99770Y325249
X100550Y335140
X103200Y330190
Y335190
X113100Y333106
X117063Y321016
X125563Y323116
Y330316
X125663Y326716
X127000Y339000
X137300Y337200
X139763Y323600
Y327800
X141211Y325515
X141300Y321500
X141263Y330216
X192037Y332480
X194537
X197037
X264179Y328060
Y335860
Y339760
X267392Y322000
X267859Y326110
Y330009
Y333909
Y337809
X271239Y320260
Y324160
Y328060
Y335860
X274619Y322209
Y326110
Y330009
Y333909
Y337809
X277999Y320260
Y328060
Y331960
Y339760
X281379Y326110
Y333909
Y337809
X284759Y324160
Y328060
Y331960
Y339760
X288139Y326110
Y333909
Y337809
X291519Y328060
Y331960
Y335860
Y339760
X294899Y322209
Y333909
Y337809
X298279Y328060
Y331960
Y339760
X301659Y322209
Y326110
Y330009
Y333909
Y337809
X305039Y320260
Y324160
Y328060
Y331960
Y339760
X308418Y322209
Y326110
Y330009
Y333909
Y337809
X311798Y320260
Y324160
Y328060
X315178Y322209
Y330009
Y333909
X318558Y320260
Y324160
Y328060
Y335860
X321938Y322209
Y330009
Y333909
Y337809
X325318Y320260
Y324160
Y328060
Y335860
Y339760
X328698Y322209
Y326110
Y330009
Y333909
Y337809
X332078Y320260
Y324160
Y328060
Y331960
Y339760
X335458Y326110
Y330009
Y333909
Y337809
X338838Y320260
Y324160
Y328060
Y331960
Y339760
X342218Y322209
Y326110
Y330009
Y333909
Y337809
X345598Y320260
Y324160
Y328060
Y331960
Y335860
Y339760
X348978Y322209
Y326110
Y330009
Y333909
Y337809
X352357Y331960
Y335860
X355737Y333909
Y337809
X357057Y320260
Y324160
X357987Y327609
X359117Y335860
Y339760
X361367Y329560
X362497Y337809
X364747Y331509
X365877Y339760
X368127Y333460
X371507Y335409
X374887Y337360
X378267Y339309
X394648Y338341
X398148
X401148
X403648
X407448Y338641
X410948
X413948
X416448
X419400Y338600
X426494Y338361
X430089Y338428
X438240Y339380
X442020Y339220
X450700Y335550
X453200
X456900Y333000
X458643Y338746
X468783Y332897
X469913Y321496
X474413Y325396
Y329296
Y333196
Y337096
X477792Y323446
Y327347
Y331247
Y335147
Y339047
X481172Y329296
Y337096
X484552Y323446
Y327347
Y335147
Y339047
X487932Y321496
Y325396
Y329296
Y333196
Y337096
X491312Y323446
Y327347
Y331247
Y335147
Y339047
X494692Y321496
Y325396
Y329296
Y333196
Y337096
X498072Y323446
Y327347
Y331247
Y335147
Y339047
X501452Y321496
Y325396
Y329296
Y333196
X504832Y323446
Y327347
Y331247
Y335147
Y339047
X508212Y321496
Y325396
Y329296
Y333196
Y337096
X511592Y323446
Y327347
Y331247
Y335147
Y339047
X514972Y321496
Y325396
Y329296
Y333196
Y337096
X518352Y323446
Y327347
Y331247
Y339047
X521731Y321496
Y325396
X525111Y335147
Y339047
X528491Y337096
X531871Y327347
Y335147
X535251Y321496
Y325396
Y329296
Y333196
X538631Y335147
Y339047
X542011Y321496
X545391Y331247
Y335147
X548771Y325396
Y329296
Y337096
X552151Y323446
X555531Y333196
X558911Y335147
X561966Y325502
X562591Y333196
X636100Y329800
X637143Y322000
Y327000
X637681Y332390
Y337390
X638790Y329500
X646272Y328800
X646800Y326100
X646900Y320100
X648900Y336600
X649000Y339400
X655900Y320500
X656000Y325100
Y329800
X658900Y339150
X660900Y329800
X666900Y329700
X667900Y339000
X672200Y329800
X674700Y339200
X678100Y324800
Y329600
X684100Y338200
X686600Y335600
X687300Y325200
X687400Y328200
X695300Y338100
X695400Y328000
X697352Y330500
Y335500
X697521Y320500
Y325500
X698600Y338900
X701100Y339000
X711900Y327700
X712400Y324400
X727474Y335363
Y338363
X729974Y335363
Y338363
X732474Y335363
Y338363
X757956Y328095
X762760Y339500
X765730Y335064
X766732Y321189
X775171Y323116
Y330316
X775271Y326716
X789432Y323900
X789500Y328000
X790900Y322000
Y326000
X790871Y330216
X842600Y331500
X845100
X847600
X882008Y321100
X913787Y328060
Y331960
Y339760
X917167Y322209
X917467Y326110
Y330009
Y333909
Y337809
X920847Y320260
Y324160
Y328060
Y335860
X924227Y322209
Y326110
Y330009
Y333909
Y337809
X927607Y320260
Y328060
Y331960
Y339760
X930987Y326110
Y333909
Y337809
X934367Y324160
Y328060
Y331960
Y339760
X937747Y326110
Y333909
Y337809
X941127Y328060
Y331960
Y335860
Y339760
X944507Y322209
Y333909
Y337809
X947887Y328060
Y331960
Y339760
X951267Y322209
Y326110
Y330009
Y333909
Y337809
X954647Y320260
Y324160
Y328060
Y331960
Y339760
X958026Y322209
Y326110
Y330009
Y333909
Y337809
X961406Y320260
Y324160
Y328060
X964786Y322209
Y330009
Y333909
X968166Y320260
Y324160
Y328060
Y335860
X971546Y322209
Y330009
Y333909
Y337809
X974926Y320260
Y324160
Y328060
Y335860
Y339760
X978306Y322209
Y326110
Y330009
Y333909
X981686Y320260
Y324160
Y328060
Y331960
Y335860
Y339760
X985066Y322209
Y326110
Y330009
Y337809
X988446Y320260
Y324160
Y328060
Y331960
Y335860
Y339760
X991826Y322209
Y326110
Y330009
Y333909
X995206Y320260
Y324160
Y328060
Y331960
Y335860
Y339760
X998586Y322209
Y326110
Y330009
Y333909
X1001965Y331960
Y335860
X1005345Y333909
Y337809
X1006665Y320260
Y324160
X1007595Y327609
X1008725Y335860
Y339760
X1010975Y329560
X1012105Y337809
X1014355Y331509
X1015485Y339760
X1016399Y324304
X1017393Y326580
X1017735Y333460
X1019893Y326580
X1021115Y335409
X1022393Y326580
X1024495Y337360
X1024893Y326580
X1025755Y328951
X1027393Y326580
X1027875Y339309
X1028393Y329580
X1044256Y338341
X1047756
X1050756
X1053702Y338404
X1102300Y336700
X1105900Y334000
X1108251Y338746
X1109200Y325100
X1113500Y323400
X1118391Y332897
X1119521Y321496
X1124021Y325396
Y329296
Y333196
Y337096
X1127400Y323446
Y327347
Y331247
Y335147
Y339047
X1130780Y329296
Y337096
X1134160Y323446
Y327347
Y335147
Y339047
X1137540Y321496
Y325396
Y329296
Y333196
Y337096
X1140920Y323446
Y327347
Y331247
Y335147
Y339047
X1144300Y321496
Y325396
Y329296
Y333196
Y337096
X1147680Y323446
Y327347
Y331247
Y335147
Y339047
X1151060Y321496
Y325396
Y329296
Y333196
X1154440Y323446
Y327347
Y331247
Y335147
Y339047
X1157820Y321496
Y325396
Y329296
Y333196
Y337096
X1161200Y323446
Y327347
Y331247
Y335147
Y339047
X1164580Y321496
Y325396
Y329296
Y333196
Y337096
X1167960Y323446
Y327347
Y331247
Y339047
X1171339Y321496
Y325396
X1174719Y335147
Y339047
X1178099Y337096
X1181479Y327347
Y335147
Y339047
X1184859Y321496
Y325396
Y329296
Y333196
Y337096
X1188239Y323446
Y335147
Y339047
X1191619Y321496
Y329296
Y333196
X1194999Y327347
Y331247
Y335147
Y339047
X1198379Y325396
Y329296
Y333196
Y337096
X1201759Y323446
Y331247
Y335147
Y339047
X1205139Y333196
X1208519Y339047
X1212200Y333196
X1319906Y338025
X1320900Y321300
X1331720Y334810
X1336336Y333825
X1346550Y322350
X1349134Y321145
X1355300Y321675
X1358500Y338400
X1359200Y322200
X1363700Y321600
X1364260Y331619
X1364300Y338300
X1367200Y321600
X1370200Y338400
X1371000Y322400
X1384024Y320225
X1388450Y331250
X1389600Y320100
X1392400Y330800
X1396470Y330014
X1400400Y335400
X1400558Y320157
X1403100Y321350
X1408250Y333000
X1408348Y336436
X1408376Y339882
X1410489Y337988
X1410550Y320800
X1413387Y320033
X1416000Y332900
Y335500
Y338100
X1443500Y327900
X1444311Y324366
X1466970Y320235
X1468399Y324930
X1470257Y321929
X1470276Y330774
X1471562Y325531
X1472450Y337500
X1472500Y334800
X1473231Y320250
X1482386Y336926
X1482550Y333600
X1483506Y326061
X1484100Y330115
X1484620Y339152
X1487000Y333300
X1487426Y330100
X1487904Y337500
X1492540Y328250
X1493240Y325828
X1495445Y338724
X1496400Y336376
X1497997Y338546
X1498600Y334800
X1501583Y339389
X1504370Y330970
X1510584Y330640
X1513796Y330680
X1514050Y327490
X1514100Y321792
X1517115Y330005
X1517600Y320940
X1521817Y330937
X1525051Y329553
X1527537Y330048
X1533228Y325000
X1538406Y330157
X1539400Y320200
X1542200Y324600
X1543700Y322600
X1544904Y334008
X1547398Y333823
X1548024Y322145
X1548000Y331361
X1548334Y325497
X1551250Y320303
X1554932Y332171
X1560024Y329200
Y331800
X1569211Y331542
Y334142
X1573950Y338050
X1575645Y320664
X1580150Y329483
X1581090Y338795
X1583794Y338767
X1589476Y322953
X1590176Y331844
X1592110Y322002
X1602776Y331304
X1608764Y322440
X1609172Y339630
X1619897Y336136
Y338636
X1620159Y332004
X1625400Y327667
X1631015Y328350
X1635355Y324228
X1638063Y326504
X1652991Y321341
Y323941
Y329059
X1653091Y326500
Y331618
X1652186Y354700
Y352100
X1650624Y357884
X1643700Y351667
X1643150Y348692
X1642712Y342347
X1642443Y344879
X1642126Y357894
X1638991Y352037
X1635503Y346046
Y340146
X1632503Y343146
X1630534Y354900
X1630408Y357603
X1629503Y346146
Y340146
X1619889Y352841
X1619897Y341136
X1610140Y358350
X1609271Y348166
X1608850Y343835
X1608020Y356500
X1590154Y354762
X1590218Y350995
X1589100Y358400
X1588551Y341410
X1587032Y350996
X1586500Y358400
Y354900
X1582859Y341112
X1580365Y341293
X1576074Y359600
X1571450Y359650
X1570574Y341776
X1566922Y359681
X1566000Y341000
X1563000
X1560500Y350000
X1557534Y353400
X1557550Y341100
X1554800
X1552500Y358500
X1550639Y350200
X1548100Y342200
X1546182Y355446
X1543528Y352446
Y349946
X1542932Y355740
X1538500Y359363
X1538478Y355894
Y353294
Y350694
X1532367Y356530
X1530033Y340799
X1528146Y349842
X1526000Y341000
X1525561Y350253
X1524746Y359217
Y356717
Y354217
X1520766Y341000
X1520429Y354379
X1520313Y357069
X1517367Y349964
X1514925Y358844
X1514265Y355542
X1511000Y350627
X1510851Y340113
X1507200Y358700
Y356000
X1507154Y353100
X1505000Y340990
X1502970Y350610
X1499829Y341250
X1498246Y357505
Y354905
Y352305
X1496000Y350000
X1495810Y341200
X1489915Y352637
X1489838Y350011
X1488479Y357767
X1487858Y340412
X1483867Y356753
X1483740Y359550
X1483172Y351806
X1482585Y340856
X1481000Y350000
X1478607Y359082
X1478163Y354940
X1472500Y341074
X1469000Y345850
X1464124Y353776
X1463942Y359742
X1463617Y357259
X1460400Y353000
X1459111Y356353
X1453900Y353350
X1453251Y356676
X1450400Y354300
X1447685Y352025
X1445510Y350327
X1415500Y353200
X1415450Y350550
X1394260Y351170
X1392500Y344600
X1391845Y348325
X1388500Y350864
X1388300Y346200
X1388208Y341489
X1384700Y359700
X1378200Y346900
X1370300Y350200
X1370200Y343900
X1364100Y350200
X1358400Y350100
X1358300Y344200
X1344731Y359567
X1339597Y349756
X1336886Y351113
X1335250Y344250
X1332600Y349900
X1332613Y346417
X1330100Y350100
X1329757Y346511
X1326300Y341309
X1326014Y347732
X1212199Y356597
Y352696
Y344896
X1205139Y340996
X1201759Y358547
Y350747
Y346847
Y342947
X1198379Y356596
Y352696
Y344896
Y340996
X1194999Y354647
Y346847
Y342947
X1191619Y352696
Y348796
X1188239Y346847
Y342947
X1184859Y356596
Y352696
Y348796
Y344896
Y340996
X1181479Y354647
Y350747
Y346847
Y342947
X1178099Y356596
Y348796
Y344896
Y340996
X1174719Y358547
Y354647
Y350747
Y346847
Y342947
X1171339Y356596
Y348796
Y344896
X1167960Y358547
Y342947
X1164580Y356596
Y340996
X1157820Y356596
Y352696
X1154440Y358547
Y354647
Y350747
Y346847
Y342947
X1151060Y356596
Y352696
Y348796
Y344896
Y340996
X1147680Y358547
Y354647
Y350747
Y346847
Y342947
X1144300Y356596
Y352696
Y348796
Y344896
Y340996
X1140920Y358547
Y350747
Y346847
X1137540Y352696
Y348796
Y344896
Y340996
X1134160Y358547
Y354647
Y350747
Y346847
Y342947
X1130780Y356596
Y352696
Y348796
Y344896
Y340996
X1127400Y358547
Y354647
Y346847
Y342947
X1124021Y356596
Y352696
Y348796
Y340996
X1120641Y358547
Y350747
Y342947
X1117261Y352696
Y348796
Y340996
X1113881Y358547
Y350747
Y346847
X1110501Y352696
X1107121Y358547
Y354647
Y346847
X1104871Y340697
X1103741Y356596
Y352696
Y348796
X1101491Y342646
X1100361Y358547
Y350747
X1098111Y344597
X1096981Y352696
X1094731Y346546
X1093601Y358547
X1091351Y348497
X1090221Y356596
Y352696
X1087971Y346546
X1086841Y358547
Y354647
X1084591Y348497
X1083462Y352696
X1081212Y346546
X1080082Y354647
X1077832Y348497
X1076702Y356596
Y352696
X1076435Y343595
X1074452Y346546
X1073322Y354647
X1071072Y348497
X1061039Y359351
X1060694Y355360
Y351460
X1054914Y347000
X1052664Y357309
Y353409
X1051534Y345160
X1049284Y359260
Y351460
X1048154Y347109
X1045904Y357309
Y353409
X1044774Y345160
X1042524Y359260
Y355360
Y351460
X1041395Y347109
X1039145Y357309
Y353409
X1038015Y345160
X1035765Y359260
Y355360
Y351460
X1034635Y343209
X1032385Y353409
Y349509
X1031255Y341260
X1029005Y359260
Y347560
X1025625Y357309
Y353409
Y345609
X1022245Y359260
Y355360
Y347560
Y343660
X1018865Y357309
Y353409
Y349509
Y345609
Y341709
X1015485Y359260
Y343660
X1012105Y357309
Y353409
Y341709
X1008725Y359260
Y351460
Y343660
X1005345Y357309
Y353409
Y349509
Y345609
X1001965Y359260
Y351460
X998586Y357309
Y353409
Y349509
X995206Y359260
Y351460
Y343660
X991826Y357309
Y353409
Y345609
Y341709
X988446Y359260
Y355360
Y351460
Y347560
X985066Y353409
Y349509
Y345609
Y341709
X981686Y359260
Y355360
Y347560
X978306Y357309
Y353409
Y349509
Y345609
Y341709
X974926Y359260
Y355360
Y347560
Y343660
X971546Y353409
Y349509
X968166Y359260
Y355360
Y351460
X964786Y357309
Y353409
Y349509
X961406Y359260
Y355360
Y351460
Y347560
X958026Y357309
Y353409
Y345609
Y341709
X954647Y355360
Y351460
Y347560
Y343660
X951267Y357309
Y349509
Y345609
X947887Y359260
Y355360
Y351460
Y343660
X944507Y353409
Y349509
Y345609
X941127Y359260
Y355360
Y351460
Y347560
Y343660
X937747Y357309
Y353409
Y349509
Y345609
Y341709
X934367Y359260
Y351460
Y343660
X930987Y357309
Y353409
Y349509
Y345609
X927607Y355360
Y347560
Y343660
X924227Y357309
Y353409
Y349509
Y345609
Y341709
X920847Y355360
Y347560
Y343660
X917467Y353409
Y349509
Y341709
X913787Y355360
Y347560
Y343660
X790900Y358200
X790867Y350024
X790871Y345716
Y343216
X790835Y354048
X789597Y356105
X789432Y352100
Y348100
X787371Y345716
Y343216
X779932Y340033
X777600Y346600
X777182Y340033
X775271Y358716
X775171Y355116
X775232Y351633
Y349133
X775171Y346616
X774347Y339983
X771700Y342501
X767477Y350708
X766732Y353189
X765116Y344512
X765144Y341508
X765007Y348363
X760500Y359800
X732474Y347663
Y344663
X729974Y347663
Y344663
X727474Y347663
Y344663
X713900Y352800
Y350300
Y347800
Y345300
Y342800
X695700Y357300
Y346300
X695644Y354644
X684900Y348000
X684194Y351206
X679194
X679000Y348000
X674600
X674194Y358467
Y351206
X669194
X669093Y348120
X664194Y351206
X664100Y348000
X659694Y351206
X658900Y348000
X654194Y351206
X654000Y348000
X649194Y351206
X648800Y348000
X639350Y339980
X563200Y356596
X562591Y352696
Y348796
Y344896
X558911Y342947
X552151Y358547
Y350747
X548771Y356596
Y352696
Y340996
X545391Y358547
Y354647
Y346847
Y342947
X542011Y352696
Y348796
X535251Y356596
Y352696
X531871Y354647
Y350747
Y346847
X528491Y356596
X525111Y358547
Y354647
Y350747
Y342947
X521731Y356596
Y348796
Y344896
X518352Y358547
Y342947
X514972Y356596
Y352696
Y348796
Y344896
Y340996
X511592Y350747
Y346847
Y342947
X508212Y356596
Y352696
Y348796
Y344896
Y340996
X504832Y358547
Y354647
Y350747
Y346847
Y342947
X501452Y356596
Y352696
Y348796
Y344896
Y340996
X498072Y358547
Y354647
Y350747
Y346847
Y342947
X494692Y356596
Y352696
Y348796
Y344896
Y340996
X491312Y358547
Y350747
Y346847
X487932Y352696
Y348796
Y344896
Y340996
X484552Y358547
Y354647
Y350747
Y346847
X481172Y356596
Y352696
Y348796
Y344896
Y340996
X477792Y358547
Y354647
Y350747
Y346847
Y342947
X474413Y356596
Y352696
Y348796
Y340996
X471033Y358547
Y350747
Y346847
Y342947
X467653Y356596
Y352696
Y348796
Y340996
X464273Y358547
Y350747
Y346847
X460893Y356596
Y352696
X457513Y358547
Y354647
Y346847
X455263Y340697
X454133Y356596
Y352696
Y348796
X451883Y342646
X450753Y358547
Y350747
X448503Y344597
X447373Y356596
Y352696
X445123Y346546
X443993Y358547
X441743Y348497
X440613Y356596
Y352696
X438363Y346546
X437233Y358547
Y354647
X434983Y348497
X433854Y352696
X431604Y346546
X430474Y354647
X428224Y348497
X427094Y356596
Y352696
X424844Y346546
X423714Y354647
X421464Y348497
X411431Y359351
X411086Y355360
Y351460
X405306Y347109
X403056Y357309
Y353409
X401926Y345160
X399676Y359260
Y351460
X398546Y347109
X396296Y353409
X395166Y345160
X392916Y359260
Y355360
Y351460
X391787Y347109
X389537Y353409
X388407Y345160
X386157Y359260
Y355360
Y351460
X385027Y343209
X382777Y349509
X381647Y341260
X379397Y359260
Y347560
X376017Y353409
Y345609
X372637Y359260
Y355360
Y347560
Y343660
X369257Y353409
Y349509
Y345609
Y341709
X365877Y359260
Y355360
Y347560
Y343660
X362497Y353409
Y341709
X359117Y359260
Y355360
X355737Y353409
Y349509
X352357Y359260
Y355360
X348978Y353409
Y349509
Y345609
Y341709
X345598Y359260
Y355360
Y343660
X342218Y353409
Y345609
X338838Y359260
Y355360
Y351460
Y347560
Y343660
X335458Y353409
Y349509
Y345609
X332078Y359260
Y355360
Y347560
Y343660
X328698Y357309
Y353409
Y349509
Y345609
X325318Y359260
Y355360
Y347560
Y343660
X321938Y353409
Y349509
X318558Y359260
Y355360
Y351460
X315178Y357309
Y353409
Y349509
X311798Y359260
Y355360
Y351460
Y347560
X308418Y357309
Y353409
Y345609
Y341709
X305039Y359260
Y351460
Y347560
Y343660
X301659Y357309
Y353409
Y349509
Y345609
X298279Y359260
Y351460
Y343660
X294899Y357309
Y353409
Y349509
Y345609
X291519Y359260
Y355360
Y351460
Y347560
Y343660
X288139Y357309
Y353409
Y349509
Y345609
Y341709
X284759Y359260
Y351460
Y343660
X281379Y357309
Y353409
Y349509
Y345609
X277999Y359260
Y351460
Y347560
Y343660
X274619Y357309
Y353409
Y349509
Y345609
Y341709
X271239Y355360
Y351460
Y343660
X267859Y353409
Y349509
Y341709
X264179Y355360
Y351460
Y343660
X195233Y348402
X141300Y353300
X141289Y349488
X141263Y345716
Y343216
X141200Y357200
X139763Y359500
Y355200
Y351400
X139582Y347800
X137763Y345716
Y343216
X129700Y340152
X128100Y346700
X125663Y358716
X125563Y355116
X125624Y351633
Y349133
X125563Y346616
X122361Y342649
X119050Y341625
X118008Y348991
X117063Y353016
X116000Y350643
X115508Y344512
X115536Y341508
X110670Y344500
X102160Y354780
X102060Y351759
X102040Y348960
X101880Y346300
X98538Y341139
X88000Y343900
X87900Y347500
X82500Y341400
X82037Y358542
X79100Y347000
X76300Y358400
X70900Y358300
X66350Y347950
X63800Y348600
X61041Y351737
X60900Y348300
X60400Y355750
X54400Y340300
X52000Y354500
X51900Y351000
X51923Y346164
X50510Y359240
X49200Y340650
X49100Y354500
X49091Y351509
X49117Y349009
X49017Y346509
Y344009
X47970Y359550
X55500Y371700
X55616Y368998
X57395Y366795
X57800Y376100
X58271Y363669
X60934Y362307
X61914Y368731
X62600Y375100
X70600Y368400
X74800Y379700
X76500Y368300
X80200Y379700
X82100Y368300
X101750Y360120
X101770Y363150
X101828Y371096
X101965Y368296
X109500Y370000
X109640Y376070
X112600Y366300
X113500Y369000
X118220Y360500
X122300Y372100
X122473Y374716
X125563Y362316
Y378616
X127420Y371590
X128500Y378700
X130585Y372085
X137763Y375216
Y377716
X139631Y379900
X141263Y362216
Y375216
Y377716
X191900Y360173
X194500Y360200
X195200Y377800
X197137Y360350
X206600Y372400
X267559Y361209
Y369010
X274619Y361209
Y365109
Y369010
Y372909
Y376809
X277999Y363160
Y367060
Y370959
Y378760
X281379Y365109
Y372909
Y376809
X284759Y363160
Y367060
Y370959
Y378760
X288139Y361209
Y365109
Y372909
Y376809
X291519Y363160
Y367060
Y370959
Y374860
Y378760
X294899Y365109
Y369010
Y372909
Y376809
X298279Y363160
Y370959
Y378760
X301659Y365109
Y369010
Y372909
Y376809
X305039Y363160
Y367060
Y370959
Y378760
X308418Y361209
Y365109
Y369010
Y372909
Y376809
X311798Y367060
Y370959
Y374860
Y378760
X315178Y361209
Y365109
Y372909
Y376809
X318558Y367060
Y370959
Y378760
X321938Y361209
Y365109
Y372909
Y376809
X325318Y363160
Y367060
Y370959
Y374860
Y378760
X328698Y365109
Y376809
X332078Y363160
Y378760
X335458Y361209
Y372909
X338838Y367060
Y370959
Y378760
X342218Y361209
Y365109
Y372909
Y376809
X345598Y367060
Y370959
Y378760
X348978Y361209
Y365109
Y372909
Y376809
X352357Y367060
Y370959
Y378760
X355737Y361209
Y365109
Y372909
Y376809
X359117Y367060
Y370959
Y378760
X362497Y361209
Y365109
Y372909
Y376809
X365877Y367060
Y370959
Y378760
X369257Y365109
Y372909
Y376809
X372637Y367060
Y370959
Y378760
X376017Y361209
Y365109
Y372909
Y376809
X379397Y367060
Y370959
Y378760
X382777Y361209
Y365109
Y372909
Y376809
X386157Y367060
Y370959
Y378760
X389537Y361209
Y365109
Y372909
Y376809
X392916Y367060
Y370959
Y378760
X396296Y361209
Y365109
Y372909
Y376809
X399676Y367060
Y370959
Y378760
X403056Y361209
Y365109
Y372909
Y376809
X411086Y374860
X411447Y363160
X411547Y365660
Y368260
X423714Y362447
Y370247
Y374146
X427094Y360496
Y364396
Y368296
Y372197
Y376096
X430474Y366347
Y374146
Y378047
X433854Y360496
Y364396
Y368296
Y372197
Y376096
X437233Y362447
Y370247
Y374146
X440613Y364396
Y368296
Y372197
X443993Y362447
Y366347
Y378047
X447373Y364396
Y368296
Y372197
Y376096
X450753Y362447
Y366347
Y370247
Y378047
X454133Y364396
Y372197
Y376096
X457513Y362447
Y366347
Y370247
Y378047
X460893Y364396
Y372197
Y376096
X464273Y362447
Y366347
Y370247
Y378047
X467653Y364396
Y368296
Y372197
Y376096
X471033Y362447
Y366347
Y370247
Y378047
X474413Y364396
Y372197
Y376096
X477792Y362447
Y366347
Y370247
Y378047
X481172Y360496
Y368296
Y372197
Y376096
X484552Y362447
Y366347
Y370247
Y378047
X487932Y360496
Y364396
Y368296
Y372197
Y376096
X491312Y362447
Y366347
Y370247
Y374146
Y378047
X494692Y360496
Y364396
Y368296
Y372197
Y376096
X498072Y362447
Y366347
X501452Y360496
Y364396
Y368296
X504832Y362447
Y366347
Y378047
X508212Y360496
X511592Y370247
Y374146
Y378047
X514972Y372197
X518352Y362447
Y366347
Y370247
Y374146
Y378047
X521731Y360496
Y364396
Y368296
Y372197
Y376096
X525111Y362447
Y366347
Y370247
Y374146
Y378047
X528491Y360496
Y364396
Y368296
Y372197
X531871Y370247
Y374146
X538631Y366347
Y370247
Y378047
X542011Y360496
Y364396
Y368296
Y372197
Y376096
X545391Y362447
Y366347
Y370247
Y374146
Y378047
X548771Y360496
Y368296
Y372196
Y376096
X552151Y374146
Y378047
X559212Y370247
Y374146
X659936Y364171
X662936
Y367171
X665936Y364171
Y367171
Y370171
X668936Y364171
Y367171
Y370171
Y373171
X670300Y375600
X671936Y367171
Y370171
Y373171
X677563Y365496
X678730Y362841
X683417Y364972
X688600Y365100
X698560Y374430
X727474Y364863
Y367463
X727574Y373463
X729974Y364863
Y367463
X730074Y373463
Y376063
X731100Y362300
X732474Y364863
Y367463
X732574Y373463
Y376063
X760140Y362819
X764131Y376747
X764159Y373743
X771400Y374400
X772443Y371976
X775121Y378616
X775171Y362316
X777100Y372000
X778000Y378700
X779882Y372033
X787321Y374916
Y377316
X789282Y379200
X789500Y360200
X790821Y374916
Y377316
X790871Y362216
X842600Y363000
X845100
X847600
X851430Y367468
X917167Y361209
Y369010
X924227Y361209
Y365109
Y369010
Y372909
Y376809
X927607Y363160
Y367060
Y374860
X930987Y361209
Y365109
Y369010
Y372909
Y376809
X934367Y363160
Y370959
Y374860
X937747Y361209
Y365109
Y369010
Y376809
X941127Y363160
Y367060
Y370959
Y374860
Y378760
X944507Y361209
Y369010
Y372909
X947887Y363160
Y367060
Y370959
Y374860
Y378760
X951267Y361209
Y369010
Y376809
X954647Y363160
Y367060
Y370959
Y374860
Y378760
X958026Y361209
Y365109
Y369010
Y372909
X961406Y363160
Y370959
Y374860
Y378760
X964786Y365109
Y369010
Y376809
X968166Y363160
Y367060
Y370959
Y374860
Y378760
X971546Y361209
Y369010
Y376809
X974926Y363160
Y367060
Y370959
Y374860
Y378760
X978306Y365109
Y376809
X981686Y363160
Y378760
X985066Y361209
Y372909
X988446Y367060
Y374860
X991826Y365109
Y369010
Y372909
Y376809
X995206Y370959
X998586Y365109
Y369010
Y376809
X1001965Y363160
Y370959
Y374860
X1005345Y365109
Y369010
Y376809
X1008725Y363160
Y370959
Y374860
X1012105Y365109
Y369010
Y376809
X1015485Y363160
Y370959
Y374860
X1018865Y365109
Y376809
X1022245Y363160
Y370959
Y374860
X1025625Y365109
Y369010
Y376809
X1029005Y363160
Y370959
Y374860
X1032385Y365109
Y376809
X1035765Y363160
Y370959
Y374860
X1039145Y365109
Y369010
Y376809
X1042524Y363160
Y370959
Y374860
X1045904Y365109
Y369010
Y376809
X1049284Y363160
Y370959
Y374860
X1052664Y365109
Y369010
Y376809
X1060694Y374860
X1073322Y362447
Y366347
Y374146
X1076702Y360496
Y368296
Y372197
Y376096
X1080082Y362447
Y366347
Y370247
Y378047
X1083462Y360496
Y368296
Y372197
Y376096
X1086841Y362447
Y366347
Y374146
X1090221Y364396
Y368296
Y372197
X1093601Y362447
Y366347
Y378047
X1096981Y360496
Y368296
Y372197
Y376096
X1100361Y366347
Y374146
Y378047
X1103741Y364396
Y368296
Y372197
X1107121Y362447
Y370247
Y374146
Y378047
X1110501Y364396
Y368296
Y372197
X1113881Y362447
Y366347
Y374146
Y378047
X1117261Y360496
Y368296
Y372197
Y376096
X1120641Y366347
Y370247
Y378047
X1124021Y364396
Y372197
Y376096
X1127400Y362447
Y366347
Y378047
X1130780Y360496
Y368296
Y372197
Y376096
X1134160Y362447
Y366347
Y370247
Y378047
X1137540Y360496
Y364396
Y368296
Y372197
Y376096
X1140920Y362447
Y366347
Y370247
Y374146
Y378047
X1144300Y360496
Y364396
Y368296
Y372197
Y376096
X1147680Y362447
Y366347
X1151060Y360496
Y364396
Y368296
X1154440Y362447
Y366347
Y378047
X1157820Y360496
X1161200Y370247
Y374146
Y378047
X1164580Y372197
X1167960Y362447
Y366347
Y370247
Y374146
Y378047
X1171339Y360496
Y364396
Y368296
Y372197
Y376096
X1174719Y362447
Y366347
Y370247
Y374146
Y378047
X1178099Y360496
Y364396
Y372197
X1181479Y370247
Y374146
X1188239Y366347
Y370247
Y378047
X1191619Y360496
Y364396
Y372197
X1194999Y362447
Y366347
Y370247
Y374146
Y378047
X1198379Y360496
Y364396
Y372197
X1201759Y374146
Y378047
X1205139Y360496
X1209219Y370247
X1209769Y374146
X1315496Y361190
X1319300Y378500
X1322100Y377800
X1325000Y377500
X1327600Y377400
X1330200Y377300
X1332650Y374450
X1332600Y377200
X1341954Y360368
X1342570Y368220
X1356466Y360680
X1358512Y371792
X1358500Y374500
X1358655Y379352
X1359600Y360800
X1360200Y377400
X1362510Y360717
X1364856Y366666
X1365731Y360698
X1371600Y368700
X1374344Y371431
X1374268Y374285
X1374300Y377885
X1376979Y370536
X1377103Y373428
X1380200Y370400
Y373100
X1380872Y378098
X1382017Y367584
X1389450Y372250
X1389500Y360500
X1392144Y364617
X1392805Y360466
X1413400Y361300
X1417217Y379129
X1417656Y367547
X1417773Y374107
X1420075Y378375
X1420515Y368585
Y373585
X1443100Y368950
X1444400Y371600
X1445100Y374900
X1448050Y374950
X1456000Y360700
X1457300Y373600
X1461016Y359965
X1463200Y362200
X1463870Y367869
X1467597Y363000
X1473255Y372654
Y376254
X1474500Y365500
X1478500
X1478612Y361670
X1483500Y365500
X1483664Y362914
X1488394Y365466
X1488479Y360367
Y362967
X1491425Y377514
X1495325
X1498246Y362705
X1498309Y360005
X1503125Y377514
X1514825
X1515328Y363389
X1519626Y365817
X1522476Y361907
X1522625Y377514
X1526525
X1529829Y362655
X1533589Y366361
X1533719Y362783
X1533790Y360283
X1538200Y364700
X1538225Y377514
X1538397Y361861
X1543300Y360900
Y363400
X1549925Y377514
X1550417Y362607
X1553825Y377514
X1557725
X1558980Y360130
X1558950Y363050
X1558996Y365817
X1561625Y377514
X1565525
X1567121Y363217
Y365817
X1569584Y378002
X1570672Y362134
X1573521Y365500
X1576380Y362890
X1581822Y365770
X1582350Y374567
X1582420Y377830
X1582500Y369600
X1587684Y362653
X1596168Y375135
X1597850Y367329
X1597900Y370000
X1598878Y376346
X1602215Y363981
X1607412Y360895
X1608146Y376171
X1609761Y372584
X1610370Y361890
X1610642Y375135
X1620447Y373926
X1630240Y365099
X1630200Y367730
X1630337Y362600
X1630476Y360103
X1630800Y378500
X1630900Y375600
X1640001Y370790
X1640266Y360500
Y365500
X1642114Y368142
X1650480Y368215
X1652186Y360600
Y365600
X1664829Y379194
X1664905Y376695
X1661243Y392943
Y390364
X1660890Y397300
X1660934Y387883
X1654861Y396637
X1654770Y399145
X1630400Y398700
Y391800
X1630300Y395300
X1630000Y381400
X1629300Y385400
X1621800Y386300
Y381500
X1621727Y395374
X1613474Y391105
X1613452Y387098
X1610828Y381387
X1608146Y380322
X1607443Y398649
X1603307Y393224
X1599100Y399100
X1598878Y380344
X1596151Y381387
X1591912Y391052
X1587683Y397414
X1586400Y392900
X1585150Y397400
X1582600Y389300
X1582124Y381164
X1582000Y396250
X1573000Y391161
X1571585Y382230
X1571375Y394414
Y387654
X1570289Y384368
X1569425Y397794
Y391034
X1567475Y394414
Y387654
Y380894
X1565525Y391034
X1563575Y394414
X1561625Y397794
Y391034
Y384274
X1559675Y394414
Y387654
X1557725Y397794
Y391034
X1555775Y394414
Y387654
Y380894
X1553825Y397794
Y391034
X1551875Y380894
X1549925Y397794
Y391034
Y384274
X1547975Y394414
Y387654
X1546025Y397794
Y391034
X1544075Y394414
Y387654
Y380894
X1542125Y397794
X1538225
Y391034
Y384274
X1536275Y394414
Y387654
Y380894
X1534325Y391034
X1532375Y394414
Y387654
Y380894
X1530425Y397794
Y391034
Y384274
X1528475Y380894
X1526659Y397500
X1526525Y391034
Y384274
X1524575Y394414
Y380894
X1520675Y394414
Y387654
Y380894
X1518725Y397794
Y391034
X1516775Y387654
Y380894
X1514825Y397794
Y391034
Y384274
X1512875Y394414
X1508975
Y387654
Y380894
X1507025Y391034
X1505075Y380894
X1503125Y397794
Y391034
Y384274
X1501175Y394414
X1499225Y391034
Y384274
X1497275Y394414
Y387654
Y380894
X1495325Y391034
Y384274
X1493375Y394414
Y387654
X1491425Y397794
Y391034
Y384274
X1489475Y394414
Y387654
X1484600Y394100
X1482000Y399035
Y395098
Y387224
Y383287
X1473083Y393770
X1472940Y384030
X1472680Y380630
X1472550Y397500
X1470800Y395200
X1470100Y392350
X1469873Y397648
X1466873
X1465500Y395400
X1464400Y390800
X1464361Y385275
X1464400Y382720
X1464273Y397648
X1459033Y395334
X1456981Y384569
X1456900Y387600
X1456750Y381850
X1446700Y387900
X1420101Y396236
X1420075Y393402
Y388402
Y383375
X1418138Y386361
X1417349Y382137
X1415000Y399000
X1413735Y396302
Y391302
X1412220Y388360
X1394760Y394720
X1394370Y384230
X1391200Y386300
X1388900Y387800
X1386800Y398900
X1384531Y382957
X1384300Y398900
X1383700Y392300
X1381800Y398900
X1381500Y396200
X1380900Y383164
X1380800Y392300
X1378207Y394568
X1375201Y396303
X1374268Y389985
X1374300Y381485
X1374207Y387468
Y384968
X1372007Y396668
X1369407
X1362250Y399160
X1362068Y393385
Y390885
X1360300Y381100
X1360200Y389000
Y384700
X1359360Y398810
X1358700Y386700
X1358568Y393385
Y390885
X1358600Y382800
X1356560Y398910
X1354024Y398985
X1351379Y399227
X1332748Y380503
X1331770Y399490
X1330758Y389785
Y386785
Y383785
X1330190Y380406
X1329064Y399556
X1327800Y383500
X1327700Y380400
X1326064Y399556
X1324872Y383682
Y380682
X1323064Y399556
X1322054Y380560
X1320423Y399579
X1243399Y398339
X1208819Y393647
Y385847
Y381897
X1201759Y389747
X1198379Y379996
X1197258Y397546
X1194999Y385847
Y381947
X1191619Y383896
X1188239Y393647
Y389747
Y385847
Y381947
X1184859Y399496
Y395596
Y391696
Y387796
Y383896
X1181479Y397546
Y393647
Y389747
Y385847
Y381947
X1178099Y399496
Y395596
Y391696
Y383896
Y379996
X1174719Y397546
Y393647
Y385847
Y381947
X1171339Y399496
Y387796
Y379996
X1167960Y397547
Y393647
Y389747
Y385847
Y381947
X1164580Y399496
Y387796
Y383896
Y379996
X1161200Y397546
Y393647
Y385847
Y381947
X1157820Y395597
Y391696
Y387796
Y379996
X1154440Y397546
Y393647
Y389747
Y385847
Y381947
X1151060Y395597
Y391696
Y387796
Y383896
Y379996
X1147680Y397546
Y393647
Y389747
Y385847
X1144300Y395597
Y391696
X1140920Y397546
Y389747
Y385847
Y381947
X1137540Y399496
Y395597
Y391696
X1134160Y393647
Y389747
Y385847
Y381947
X1130780Y395596
Y391696
Y379996
X1127400Y389747
Y385847
Y381947
X1124021Y391696
Y387796
Y379996
X1120641Y393647
Y385847
Y381947
X1117261Y391696
X1113881Y397546
Y393647
Y385847
Y381947
X1110501Y395595
Y391696
Y387796
Y379996
X1107121Y389747
Y385847
Y381947
X1103741Y391696
Y383896
Y379996
X1100361Y397547
Y393647
Y389747
Y385847
X1096981Y387796
Y383896
Y379996
X1093601Y397546
Y393647
Y389747
Y385847
X1090221Y395595
Y391696
Y383896
Y379996
X1086841Y389747
Y385847
Y381947
X1083462Y391696
Y387796
Y379996
X1080082Y393647
Y385847
Y381947
X1078962Y399496
X1076702Y391696
Y387796
Y379996
X1073323Y397548
X1073322Y389747
Y385847
Y381947
X1060694Y390460
X1052664Y392410
Y388509
Y380709
X1049284Y382660
X1045904Y388509
Y380709
X1042524Y390460
Y386560
Y382660
X1040265Y394359
X1039145Y388509
Y380709
X1035765Y386560
Y382660
X1032385Y388509
Y380709
X1029005Y390460
Y386560
Y382660
X1025625Y392410
Y388509
Y380709
X1022245Y386560
Y382660
X1018865Y392410
Y388509
Y380709
X1015485Y382660
X1012105Y392410
Y388509
Y380709
X1008725Y386560
Y382660
X1005345Y392410
Y388509
Y380709
X1001965Y386560
Y382660
X998586Y392410
Y388509
Y380709
X995206Y390460
Y386560
Y382660
X991826Y388509
Y380709
X988446Y382660
X985066Y384609
Y380709
X974926Y386560
X974066Y399911
X971546Y380709
X968166Y394359
Y390460
Y386560
Y382660
X964786Y392410
Y388509
X961406Y386560
Y382660
X958026Y388509
Y384609
Y380709
X954647Y394359
X951267Y388509
Y384609
Y380709
X947887Y398260
Y394359
Y390460
Y386560
X944507Y396309
Y388509
Y384609
Y380709
X941127Y398260
Y394359
Y390460
Y382660
X937747Y392410
Y388509
Y384609
Y380709
X934367Y398260
Y394359
Y390460
Y382660
X930987Y396309
Y388509
Y384609
Y380709
X927607Y398260
Y394359
Y390460
Y386560
Y382660
X924227Y392410
Y380709
X920847Y398260
Y394359
Y390460
Y382660
X917467Y388509
X917100Y380709
X847577Y381842
X840871Y391380
X837272Y391420
X790900Y393400
Y389300
Y385300
Y381100
X789582Y383200
X789500Y391300
Y387300
X775221Y390716
X775182Y383633
Y381133
X775121Y394316
Y387116
X767155Y385550
X766643Y382724
X764957Y380363
X758952Y384100
X732000Y380000
X691240Y390039
X687427Y384926
X686619Y392600
X683100Y392200
X679523Y385808
X679385Y388705
X676900Y381800
X649600Y391200
X559212Y393647
Y385847
Y381947
X555531Y387797
X548771Y383896
Y379996
X545391Y397546
Y385847
Y381947
X542011Y383896
Y379996
X538631Y393647
Y389747
Y385847
Y381947
X535251Y399496
Y395597
Y391696
Y387796
Y383896
X531871Y397546
Y393647
Y389747
Y385847
X528491Y399496
Y395597
Y391696
X525111Y397546
Y393647
Y381947
X521731Y399496
Y379996
X518352Y397546
Y389747
Y385847
Y381947
X514972Y399496
Y383896
Y379996
X511592Y397546
Y393647
Y385847
Y381947
X508212Y395597
Y391696
Y387796
Y379996
X504832Y397546
Y389747
Y381947
X501452Y395597
Y391696
Y387796
Y383896
Y379996
X498072Y397546
Y393647
Y389747
Y385847
X494692Y395597
Y391696
X491312Y397546
Y389747
Y385847
Y381947
X487932Y399496
Y395597
Y391696
Y387796
Y379996
X484552Y393647
Y385847
Y381947
X481172Y395596
Y391696
Y387796
Y379996
X477792Y389747
Y385847
Y381947
X474413Y391696
Y387796
Y379996
X471033Y393647
Y389747
Y385847
Y381947
X467653Y391696
Y383896
X464273Y397546
Y393647
Y389747
Y385847
Y381947
X460893Y395595
Y391696
Y387796
Y379996
X457513Y389747
Y385847
Y381947
X454133Y391696
Y387796
Y379996
X450753Y397547
Y393647
Y385847
Y381947
X447373Y391696
Y387796
Y379996
X443993Y397546
Y393647
Y385847
Y381947
X440613Y395595
Y391696
Y387796
Y379996
X437233Y389747
Y385847
Y381947
X433854Y391696
Y383896
Y379996
X430474Y393647
Y389747
Y385847
X429354Y399496
X427094Y391696
Y383896
Y379996
X423715Y397548
X423714Y389747
Y385847
Y381947
X411086Y390460
X403056Y392410
Y388509
X399676Y390460
Y382660
X396296Y388509
Y384609
X392916Y390460
Y382660
X390657Y394359
X389537Y388509
Y384609
X386157Y382660
X382777Y388509
Y384609
X379397Y390460
Y382660
X376017Y392410
Y388509
Y384609
X372637Y390460
Y382660
X369257Y392410
Y388509
Y384609
X365877Y382660
X362497Y392410
Y388509
Y384609
X359117Y382660
X355737Y392410
Y388509
Y384609
X352357Y386560
Y382660
X348978Y392410
Y388509
X345598Y390460
Y382660
X342218Y388509
Y384609
X338838Y382660
X335458Y384609
Y380709
X325318Y386560
X324458Y399911
X321938Y380709
X318558Y394359
Y390460
Y386560
Y382660
X315178Y392410
Y388509
X311798Y386560
Y382660
X308418Y388509
Y384609
X305039Y394359
Y382660
X301659Y388509
Y384609
X298279Y398260
Y394359
Y390460
Y386560
Y382660
X294899Y396309
Y392410
Y384609
X291519Y398260
Y390460
Y386560
Y382660
X288139Y396309
Y392410
Y384609
Y380709
X284759Y398260
Y390460
Y386560
Y382660
X281379Y396309
Y392410
Y384609
X277999Y394359
Y390460
Y386560
Y382660
X274619Y392410
Y380709
X271239Y390460
Y382660
X267859Y388509
X267492Y380709
X195200Y380300
X141263Y394216
Y390416
X141261Y385876
X141300Y381800
X139900Y388000
X139763Y384000
X139736Y392300
X125663Y390716
X125563Y394316
Y387116
X125624Y383633
Y381133
X118629Y381193
X117063Y385016
X116000Y382643
X109924Y393848
X107224
X97472Y380934
X93712Y380507
X90518Y388828
X85609Y385234
X77300Y390600
X74800Y383114
X67400Y391690
X67230Y397380
X65000Y383000
X64725Y396645
Y391645
X61000Y383000
X60565Y380131
X57500Y388100
X54900Y389400
X46100Y413520
Y416271
X49265Y418995
X51500Y406000
X51645Y416281
X51890Y418970
X54244Y405624
X54662Y416478
X56383Y408163
X57471Y410749
X63024Y405636
X64007Y408276
X65384Y403258
X67710Y402040
X103100Y411800
X110397Y402603
X110452Y407092
X117363Y417416
X119016Y414201
X119100Y411600
X119300Y400900
X119398Y406348
X121981Y405573
X122242Y419199
X148300Y414600
X148666Y417397
X150650Y409860
X151909Y413267
X153392Y404000
Y407500
X157862Y416012
X167640Y404842
X167680Y408440
X172697Y407196
X174609Y404009
X177689Y404109
X180799Y404049
X288139Y400209
X302608Y402421
X320808Y401941
X357987Y402800
X378267
X391787
X406568Y402471
X423715Y401449
X428224Y407800
X443993Y401447
Y405347
X447091Y407782
X464273Y401447
Y405347
X467653Y407296
X471033Y401447
X484552Y405347
X487932Y403396
X491312Y401447
X514972Y403396
X521731
X525111Y401447
Y405347
X528491Y403396
X531871Y401447
Y405347
X538750Y406200
X619700Y419500
X619800Y416200
X622100Y417900
X624600Y419400
X687400Y411200
X690040Y412030
X703876Y414949
X705850Y417093
X708011Y419078
X708346Y415859
X710423Y417423
X712980Y417900
X748085Y409838
Y412338
X750585Y409838
Y412338
X753085Y409838
Y412338
X755487Y409903
Y412403
X757826Y411667
Y414167
X760326Y411667
Y414167
X762989Y411728
X763069Y414441
X763333Y400212
X766200Y417005
X766394Y414397
X768080Y418780
X772300Y403520
X797000Y404700
X797200Y409830
X798500Y412600
X800610Y415000
X805367Y407400
X805600Y403900
X824000Y402863
X827800
X832300
X924227Y400209
X937747
X952216Y402421
X970416Y401941
X1007595Y402800
X1027875
X1041395
X1056176Y402471
X1073323Y401449
X1077832Y407800
X1093601Y401447
Y405347
X1096699Y407782
X1113881Y401447
Y405347
X1117261Y407296
X1120641Y401447
X1134160Y405347
X1137540Y403396
X1164580
X1167960Y401447
Y405347
X1171339Y403396
X1174719Y401447
Y405347
X1178099Y403396
X1181479Y405347
X1185989Y407800
X1192200Y409550
X1195555Y405773
X1198029Y405411
X1246010Y400110
X1249230Y402022
X1316820Y418900
X1317788Y400062
Y402562
X1319320Y418900
X1320288Y402062
X1320400Y404524
X1322217Y419004
X1323288Y402062
X1323400Y404524
X1324736Y419074
X1326288Y402062
X1326400Y404524
X1327236Y419030
X1329288Y402062
X1329400Y404524
X1329736Y419004
X1331856Y401995
X1331973Y404580
X1332236Y419004
X1334967Y419001
X1352239Y401593
X1352338Y404153
X1354681Y401444
X1354982Y404154
X1357542Y401381
X1357880Y403760
X1358910Y408480
X1358980Y406060
X1358990Y411040
X1360450Y402100
X1361558Y410527
X1363250Y401700
X1364403Y410496
X1366984Y410481
X1369907Y410513
X1371200Y402100
X1372535Y410512
X1374300Y402053
X1375239Y410590
X1376800Y402053
X1377928Y410451
X1379252Y401343
X1380449Y410479
X1381752Y401343
X1382849Y410471
X1384252Y401343
X1385416Y410502
X1386752Y401343
X1388085Y410479
X1393900Y412500
Y415000
X1395725Y417193
X1396900Y412500
Y415000
X1402520Y413246
X1402725Y408136
X1404558Y416575
X1405423Y408281
Y413281
X1407158Y416575
X1412447Y416368
X1414982Y417040
X1437897Y402315
X1439350Y406900
X1439651Y412466
X1439813Y409422
X1439934Y403730
X1442830Y406472
X1443252Y409029
X1448800Y416500
X1452699Y404060
X1464300Y404900
X1465048Y402370
X1466382Y406773
X1467401Y411557
X1468048Y402370
X1469382Y406773
X1470106Y412152
X1470800Y402250
X1471900Y406900
X1472688Y412055
X1482000Y406909
Y410846
Y414783
Y418720
X1483950Y401650
X1485250Y408017
X1487525Y404554
Y411314
X1491425Y404554
Y411314
X1495325
X1497275Y401174
X1497273Y407610
X1497275Y414694
X1499225Y411314
X1501175Y407934
X1501219Y416596
X1503125Y404554
X1503128Y419892
X1505075Y407934
X1508975Y401174
X1509200Y410450
Y413600
Y416750
Y419900
X1510925Y404554
X1512350Y410450
Y416750
Y419900
X1512875Y401174
X1512954Y407653
X1515500Y413600
Y416750
Y419900
X1516700Y409900
X1516775Y401174
X1518650Y413600
Y416750
Y419900
X1518700Y406500
X1520675Y401174
X1521800Y419900
X1524575Y401174
Y407624
X1524950Y413600
X1525000Y416750
X1524950Y419900
X1526525Y404554
X1528100Y410550
Y413700
X1528475Y407934
X1531250Y419900
X1532375Y401174
Y407934
X1534325Y404554
X1534400Y413500
Y416750
Y419900
X1536275Y407934
X1537550Y413600
Y416750
Y419900
X1538225Y404554
X1540175Y407934
X1540700Y410450
Y413600
Y416750
Y419900
X1542125Y404554
X1543850Y413600
Y416750
X1544150Y409900
X1546025Y404554
X1547000Y416750
X1549926Y411312
X1549950Y404490
X1551875Y407934
Y414694
X1553825Y411314
Y418074
X1555775Y401174
Y414694
X1557725Y404554
X1559675Y401174
Y407934
Y414694
X1561625Y418074
X1563575Y401174
Y407934
Y414694
X1565525Y411314
X1567475Y401174
Y407934
X1569425Y404554
Y411314
X1571366Y401154
X1583208Y404941
Y412815
Y416752
X1587000Y411976
X1587968Y403368
X1589500Y412035
X1590581Y404170
X1591430Y409440
X1595200Y412700
X1595800Y405900
X1601060Y401010
X1603719Y412000
X1603650Y415469
X1612500Y411800
X1612825Y405438
Y408974
X1617900Y409900
X1621347Y415297
X1622100Y400600
X1630120Y418887
X1630386Y413942
X1630550Y401300
X1630750Y404800
X1634400Y412900
X1634500Y418500
X1654809Y401645
X1660834Y404934
X1660972Y401447
X1667946Y412987
X1668000Y416200
X1668100Y418700
X1933100Y436200
X1930100
X1927100
X1920700Y435600
X1917700
X1914700
X1910500
X1907500
X1675120Y439731
X1669076Y438281
X1667809Y427809
X1667729Y424621
X1667588Y434149
X1667649Y430849
X1664762Y438035
X1647200Y430450
X1640625Y429460
X1639774Y439486
X1639500Y435700
Y433200
X1630150Y427663
X1621182Y427091
X1621010Y435870
X1621044Y433364
X1612250Y435500
Y432500
X1611935Y429515
X1611418Y422971
X1603050Y432523
X1603000Y435500
Y422971
X1593400Y432200
X1590037Y432515
X1589396Y425674
X1587559Y423835
X1587238Y432593
X1585560Y421324
X1584233Y427947
X1583773Y436137
X1581939Y426594
X1571375Y436786
X1569425Y431594
Y424834
X1567475Y436786
Y421454
X1565525Y431594
X1563575Y428214
X1561625Y431594
Y424834
X1559675Y436786
Y421454
X1557725Y424834
X1555775Y436786
Y421454
X1551990Y421158
X1551875Y436786
Y428214
X1549964Y424753
X1549925Y431594
X1547754Y430351
Y427884
X1547755Y423570
Y421138
X1547000Y435650
X1543950Y438800
X1543850Y435650
Y429350
Y426200
X1540700Y438800
Y435650
Y429350
Y426200
Y423050
X1537550Y438800
Y435650
Y429350
Y426200
Y423050
X1534400Y438800
Y435650
Y429350
Y426200
Y423050
X1531250Y438800
Y435650
Y429350
Y426200
Y423050
X1524950Y438800
Y435650
Y429350
Y426200
Y423050
X1518650Y438800
Y435650
Y429350
Y426200
Y423050
X1515500Y438800
Y435650
Y429350
Y426200
Y423050
X1512350Y438800
Y435650
Y429350
Y426200
Y423050
X1509200Y438800
Y435650
Y429350
Y426200
Y423050
X1506059Y429249
X1505605Y423604
X1505462Y434630
X1505459Y421107
X1505392Y437133
X1503125Y433406
Y424834
X1501175Y436786
Y428214
X1499225Y424834
X1497275Y436786
Y428214
X1497200Y421200
X1495325Y433406
Y424834
X1491425Y433406
X1491400Y424600
X1489475Y436786
Y428214
X1487500Y424600
X1483818Y430597
X1483400Y438100
X1482500Y434600
X1482000Y426595
Y422658
X1472800Y420689
X1472530Y432731
X1472449Y439421
X1472400Y428063
X1470262Y420711
X1469931Y432842
X1469900Y428013
X1467355Y432919
X1467290Y428013
X1467262Y420711
X1464731Y432942
X1464600Y428000
X1464525Y420014
X1462131Y432851
X1459478
X1459300Y430000
X1448800Y427800
X1448000Y437000
Y431500
X1445100
X1445000Y437000
X1439000Y423000
X1435479Y423107
X1431900Y437100
X1429000Y437059
X1415146Y421946
X1412545Y421974
X1411900Y434775
Y429775
X1409300Y434775
Y429775
X1408225Y438233
X1407158Y421575
X1404558
X1403998Y434775
Y429775
X1401398Y434775
Y429775
X1395100Y432500
Y427500
X1389900Y427400
X1385100Y437500
Y432500
Y427500
X1380100Y437500
X1375100
X1370100
X1365100
Y432500
Y427500
X1355100Y437500
Y432500
Y427500
X1350100Y437500
X1345100
X1340100Y432500
Y427500
X1335100Y432500
Y427500
X1334889Y421400
X1332389
X1330100Y432500
Y427500
X1329889Y421400
X1327389Y421426
X1325100Y432500
Y427500
X1324889Y421470
X1322370Y421400
X1320100Y432500
Y427500
X1316820Y421400
X1315100Y432500
Y427500
X1310100Y432500
Y427500
X1305181Y427834
X1305100Y432500
X1300438Y433001
X1300315Y427902
X1296468Y437500
X797780Y423484
X777979Y436516
X775417Y435799
X749640Y431797
X748500Y438900
X746151Y433077
X713493Y420449
X710600Y420267
X690600Y437500
Y432500
X685600
X680370Y427770
X640300Y437600
X637300Y437200
X634200Y436800
X629600Y425100
X627000Y423436
X626737Y421000
X625200Y425400
X624300Y422100
X622900Y424200
X621800Y421100
X619680Y422600
X148409Y422239
X123441Y421795
X63600Y429000
X63630Y424280
X61005Y429305
Y424305
X51890Y424470
X49265Y423995
X43550Y431300
X40965Y429434
X37550Y425400
X35900Y423500
X24447Y439354
X21397
X20075Y424850
X17025
X12025Y427900
Y424850
X7025Y427900
Y424850
X2025Y427900
Y424850
X-17014Y455604
X7736Y441785
X10786
X11100Y446200
X15786Y441785
X18836
X21397Y444354
X24447
X32450Y454050
X35100Y453900
X573867Y459903
X584076Y443828
X586136Y446335
X588285Y448306
X592216Y445152
X595070Y447970
X609191Y451454
X615300Y457900
X728940Y457806
X739933Y447401
X747950Y441600
X1285769Y440062
X1286831Y443058
X1288671Y445338
X1300100Y442500
X1305100
Y452500
Y457500
X1310100Y442500
Y452500
Y457500
X1315100Y442500
Y452500
Y457500
X1320100Y442500
Y452500
Y457500
X1325100Y442500
Y452500
Y457500
X1330100Y442500
Y452500
Y457500
X1335100Y442500
Y447500
Y452500
Y457500
X1340100Y442500
Y447500
Y452500
Y457500
X1345100Y442500
X1349800Y458200
X1350100Y442500
Y447500
Y452500
X1355100Y442500
X1360100Y447500
Y452500
Y457500
X1365100Y442500
Y447500
Y452500
X1369034Y458075
X1370100Y442500
Y447500
Y452500
X1375100Y442500
Y452500
X1379857Y458108
X1380100Y442500
Y447500
Y452500
X1385100Y442500
Y447500
Y452500
X1389900Y447400
X1390100Y457500
X1395100Y447500
X1395375Y457561
X1397975
X1398275Y453561
X1402775
Y457561
X1405375Y453561
X1405608Y456761
X1408225Y441000
X1410475Y453561
Y457561
X1412375Y443545
X1412484Y440748
X1413075Y457561
X1413300Y454400
X1414107Y447267
X1429000Y442600
Y448000
X1429100Y453400
X1431900Y442600
Y448000
Y453500
X1444500Y448000
X1444800Y442500
X1447500Y448000
X1447700Y442500
X1451400Y454100
Y459800
X1454000Y454100
Y459800
X1456600Y454100
Y459800
X1458300Y442675
X1459000Y449997
X1459200Y454100
Y459800
X1461600Y449997
X1461800Y454100
Y459800
X1464200Y449997
X1464400Y454100
Y459800
X1466800Y449997
X1467000Y454100
Y459800
X1469400Y449997
X1472000
X1482603Y442418
X1483115Y454379
X1483200Y450455
X1483375Y458375
X1485300Y443484
X1487525Y440166
Y453686
X1489475Y443546
Y450306
X1491425Y440166
Y446926
Y453686
X1493375Y450306
Y457066
X1495325Y440166
Y446926
Y453686
X1497275Y443546
Y450306
Y457066
X1501175Y443546
X1501200Y450600
X1501175Y457066
X1503125Y440166
Y446926
Y453786
X1505075Y457066
X1505442Y443900
X1505715Y441368
X1505714Y448145
X1508975Y457066
X1509200Y441950
Y445100
Y454550
X1512350Y441950
Y445100
X1512400Y454500
X1515389Y451400
X1515500Y441950
Y445100
X1516775Y457066
X1518650Y448250
X1518675Y451425
X1520675Y457066
X1521800Y441950
Y445100
Y448250
Y451400
X1524575Y457066
X1524950Y441950
Y445100
Y448250
X1528147Y454546
X1528475Y457066
X1531250Y441950
Y445100
Y448250
Y451400
X1532349Y455200
X1534400Y441950
Y445100
Y448250
Y451400
X1536300Y455200
X1537550Y441950
Y445100
Y448250
Y451400
X1540175Y457066
X1540700Y441950
Y445100
Y448250
Y451400
X1540653Y454588
X1543850Y441950
Y445100
Y451400
X1544075Y457066
X1547975
X1549925Y440166
Y446926
X1549938Y453714
X1551875Y450306
Y457066
X1553825Y440166
Y446926
Y453686
X1555775Y443546
Y457066
X1557725Y446926
Y453686
X1559595Y450631
X1559675Y443546
Y457066
X1561625Y446926
X1563575Y457066
X1565525Y440166
X1567475Y450306
Y457066
X1569425Y440166
Y446926
Y453686
X1571375Y443546
Y457066
X1582200Y456200
X1582300Y446100
X1583208Y452185
X1585920Y452368
X1587573Y445300
X1587550Y456550
X1588632Y452151
X1588870Y440546
X1591344Y452134
X1591446Y440472
X1591350Y445300
X1596500Y455500
X1600400Y446100
X1602600Y444287
X1611638Y454809
X1612100Y446000
X1612183Y442623
X1612256Y440088
X1618800Y453400
X1621000Y440500
Y452000
X1621226Y445026
X1630219Y446000
X1630200Y454675
Y457175
X1630276Y449517
X1630300Y452100
X1639750Y445477
X1639822Y453140
X1640000Y456900
X1640100Y459700
X1646540Y441240
X1646480Y443880
X1646525Y447590
X1646469Y450090
X1646451Y452590
X1661549Y451251
X1661522Y453751
X1661470Y456251
X1664762Y440735
Y443735
X1667462Y440735
X1669816Y443953
Y446453
Y448953
X1669962Y440735
X1673064Y446022
X1673068Y448522
X1673074Y453185
X1673550Y442696
X1675744Y456200
X1676041Y458884
X1676287Y447244
X1676304Y449794
X1678303Y442765
X1681154Y449286
X1681215Y451786
X1681192Y454286
X1684435Y456832
Y459421
X1716037Y444550
X1718587
X1719317Y441947
X1721990Y444521
X1724369Y441601
X1724590Y444521
X1727620Y444380
X1730996Y442804
X1737150Y450850
X1737795Y448100
X1740963Y448476
X1743169Y450408
X1748169
X1750393Y448037
X1753543Y448100
X1755767Y450408
X1760767
X1762992Y447938
X1766100Y447900
X1768366Y450408
X1773366
X1775590Y448100
X1778740
X1780964Y450408
X1785964
X1788189Y448300
X1791338Y448400
X1793563Y450408
X1798563
X1800787Y447943
X1804000Y447900
X1806161Y450408
X1811161
X1813385Y447945
X1816535Y448300
X1818760Y450408
X1823760
X1825984Y448030
X1828600Y450100
X1831495Y450600
X1836495
X1838768Y454120
X1839400Y450440
X1841630Y454321
X1844630
X1847185Y454368
X1858633Y452803
X1859059Y448076
X1860158Y450322
X1863137Y452710
X1864300Y447900
X1866050Y451100
X1867500Y447900
X1868015Y452987
X1870815Y453022
X1872860Y447950
Y450550
X1875900Y453600
X1878100Y450200
X1882677Y447930
X1895275Y454422
X1898425Y447930
Y454422
X1901574Y447930
Y454422
X1904724Y447930
Y454422
X1907874Y448400
Y454422
X1911023Y448400
X1914173Y448200
X1917322Y447930
X1920472
X1929000Y445800
X1935300Y450600
X1939845Y445055
X1942000Y440500
X1970270Y474640
X1957212Y479521
X1957063Y474769
X1948200Y474300
X1945000Y474000
X1939000Y479400
Y476600
X1937430Y464785
X1929480Y472880
X1919510Y479200
Y475100
X1910500Y475000
Y472000
X1905010Y479410
X1904300Y470300
X1904200Y472700
X1901800Y470200
X1901700Y472600
X1900890Y477200
X1899200Y470200
X1899100Y472600
X1896800Y470200
X1896700Y472600
X1894200Y470200
X1894100Y472600
X1881285Y467049
X1877407Y479046
X1876945Y471316
X1872908Y471338
X1868167Y467855
X1861300Y466800
X1859600Y476200
X1857480Y466800
X1857450Y473654
X1855206Y471112
X1845330Y466870
X1843750Y475724
X1842857Y468630
X1840750Y475724
X1837857Y468630
X1837300Y472276
X1835550Y466870
X1832301Y467005
X1829967Y476927
X1825297
X1824960Y473980
X1822852Y467005
X1819702
X1817375Y478320
X1812375
X1810254Y467005
X1807104
X1806600Y471055
X1806525Y473955
X1801525
X1801500Y471055
X1797655Y467005
X1795164Y476406
X1794975Y479300
X1794505Y467005
X1789975Y479300
X1789774Y476403
X1785057Y467005
X1781907
X1779700Y472100
X1779300Y475055
X1774300
X1773500Y472100
X1772459Y467005
X1769309
X1767300Y472700
X1766700Y475655
X1761700
X1760900Y472800
X1759860Y467005
X1756710
X1747262
X1744112
X1734663
X1728700Y470200
X1722347Y471811
X1719089Y472104
X1687741Y466988
X1680500Y473325
X1679145Y461950
X1678001Y473205
X1672265Y473600
X1668843Y465060
X1667674Y467271
X1665047Y467257
X1655790Y476593
X1633359Y472859
X1633075Y470174
X1623814Y471400
X1623705Y467855
X1623749Y464213
X1622700Y461900
X1620500Y475000
Y463727
X1619607Y469945
X1617700Y475957
X1616607Y469945
X1615061Y463157
X1614000Y475970
Y469500
X1611642Y461877
X1611506Y474768
X1604200Y464387
X1601557Y479225
X1598700
X1597178Y472226
X1594280Y472370
X1590580
X1587970
X1587475Y460210
X1584970Y472370
X1584975Y460210
X1584200Y462610
X1582200Y460310
X1580370Y462090
X1571375Y470586
X1571390Y464480
X1569425Y473966
Y460446
X1567475Y470586
X1563575Y477346
X1561625Y460446
X1557725Y473966
X1555775Y477346
Y470586
Y463826
X1553825Y473966
Y467206
X1551875Y477346
Y463826
X1549925Y473966
Y460446
X1547975Y477346
Y470586
Y463826
X1546025Y473966
Y467206
X1544075Y477346
Y470586
Y463826
X1542125Y473966
Y467206
X1540175Y477346
Y470586
Y463826
X1538225Y473966
Y467206
Y460446
X1536275Y470586
X1534325Y467206
Y460446
X1532375Y477346
Y470586
Y463826
X1530425Y473966
Y460446
X1528475Y477346
Y470586
X1526525Y473966
Y467206
Y460446
X1524575Y470586
Y463826
X1522625Y473966
Y467206
Y460446
X1518725Y473966
Y467206
Y460446
X1516775Y470586
Y463826
X1514825Y473966
Y460446
X1510925Y473966
Y460446
X1508975Y477346
Y470586
X1507025Y473966
Y460446
X1505075Y477346
Y470586
X1503125Y473966
Y467206
Y460446
X1501175Y477346
Y470586
Y463826
X1499225Y473966
X1497275Y477346
Y470586
Y463826
X1495325Y467206
Y460446
X1493375Y477346
Y470586
Y463826
X1491425Y473966
Y467206
Y460446
X1489475Y477346
Y470586
Y463826
X1487525Y473966
X1485100Y469900
X1485030Y463690
X1482200Y477800
X1482000Y469902
Y462028
X1467000Y465500
X1464400
X1461800
X1459200
X1456600
X1454000
X1451400
X1442141Y477623
X1439314Y477723
X1436396Y477691
X1418341Y477323
X1415800Y477500
X1413041Y477423
X1362560Y463478
X1354462Y474141
X1350500Y475100
X1347546Y476897
X1347196Y472941
X1346739Y463615
X1344090Y463630
X1341528Y463528
X1329419Y469337
Y464337
X1326877Y469279
X1326626Y464400
X1323815Y463543
X1322360Y472592
X1322260Y477492
X1321172Y464474
X1319738Y477497
X1319699Y472327
X1318054Y460507
X1304200Y466600
Y462030
X1301240Y476228
X1301000Y466500
Y460900
X1272830Y471660
X1271571Y479000
X1271640Y474420
X1262900Y466504
X1262700Y461804
X1259800Y463300
X1258140Y474540
X1258126Y469540
X1256130Y467820
X1255530Y474770
X662181Y479149
X659770
X657227Y479116
X648500Y477400
X639120Y475620
X637148Y472809
X634967Y470790
X627000Y478300
X623660Y466746
X623400Y476300
X620400Y463990
X619390Y469450
X619260Y466610
X618800Y474500
X611250Y476750
X608800Y473475
Y468475
Y463475
X607012Y465997
X605826Y475894
Y473394
X582912Y468948
X581032Y467202
X575614Y461694
X89497Y479201
X72603Y474072
X71050Y478670
X67477Y477940
X66016Y468350
X65450Y475610
X24591Y479139
X17000Y475500
X14500
X11972Y475417
X10365Y461602
X5100Y478330
X5000Y469000
X2350Y469650
X2450Y460000
X2160Y479000
X-1000
X-5690Y467840
X-6100Y464840
X-6104Y461190
X-11490Y473840
X-14190
X-14690Y471140
X-17084Y467626
X-19802Y476738
X-19783Y481286
X-16700Y497400
X-13500Y486400
X-9900
X-6650Y487800
X-4350Y482100
X-900Y482300
X2485Y498185
X2589Y481983
X5689
X10443Y490649
X13700Y498500
X21000Y495800
X26780Y488910
X31477Y482788
X34300Y482890
X37568Y482836
X40132Y499800
X40185Y482918
X47800Y487600
X57302Y495442
X59731Y480066
X60202Y495342
X92326Y480398
X94998Y481612
X111961Y499877
X112427Y497225
X233292Y495900
Y498500
X236892Y490800
Y493400
X239492Y498500
X239592Y495900
X243392Y493094
Y495694
X247177Y490514
X247228Y493209
Y495909
X247177Y498514
X252313Y490514
Y493214
Y495814
Y498514
X257392Y495800
X257478Y498487
X260824Y491044
Y493744
X264192Y495800
X264171Y498487
X267584Y491219
Y493919
X271092Y495944
Y498644
X273992Y491144
Y493744
X277557Y495944
Y498644
X280203Y490644
Y493244
X284024Y490644
X284039Y493344
Y495944
X284024Y498644
X289124Y490644
Y493344
Y495944
Y498644
X294289Y490444
X294392Y493100
X297835Y494944
Y497644
X301092Y490700
Y493300
X304392Y494700
Y497300
X311701Y499136
X324187Y499793
X326797Y499767
X326922Y497170
X433192Y497650
X435192Y499400
X488384Y495887
Y498487
X491430Y491144
X491380Y493744
X494777Y495887
Y498487
X497723Y490894
Y493494
X501560Y490867
Y493467
Y496167
Y498867
X506644Y490867
Y493567
Y496167
Y498867
X511712Y495800
X511809Y498487
X514755Y491044
Y493744
X517892Y495800
X517902Y498487
X521048Y491144
Y493844
X524595Y495787
Y498387
X528241Y490944
X528191Y493544
X530792Y495787
Y498387
X534534Y490794
Y493394
X538370Y490609
Y493209
Y495909
Y498609
X543455Y490909
Y493509
Y496209
Y498909
X548492Y495800
Y498400
X551366Y490744
Y493344
X554792Y495887
Y498487
X558659Y493444
Y496144
X605249Y480891
X605206Y483291
X609284Y480055
X609470Y484060
X612000Y484000
X612515Y498752
X618430Y491550
X625430Y490100
X625569Y481568
X628700Y482000
X629300Y490000
X632113Y496892
X636500Y493924
X639197Y490367
X641150Y484300
X646200Y499700
X649600Y492400
X653800Y496600
X656050Y489500
X656100Y486900
X656900Y482290
X659070Y488709
X660500Y492000
X666500Y484600
Y487600
X669500Y481600
Y484600
X674300Y489500
X675080Y485570
X676900Y489400
X677800Y485600
X679700Y489400
X680300Y485700
X688202Y497736
X689825Y491755
Y494255
X691000Y498200
X693604Y491803
Y494303
X696000Y496800
X703028Y492600
Y495600
X706028Y492600
Y495600
X707511Y483439
X708700Y499400
X709028Y495600
X710137Y483583
X711339Y499478
X720300Y485800
X721301Y488200
X723748Y499091
X723792Y489148
X728373Y488356
X731339Y489319
X738648Y492050
X743483Y492937
X743524Y499674
X746024
X748524
X750931Y499916
X882900Y495900
Y498500
X886500Y490800
Y493400
X889100Y498500
X889200Y495900
X893000Y493094
Y495694
X896785Y490514
X896836Y493209
Y495909
X896785Y498514
X901921Y490514
Y493214
Y495814
Y498514
X907000Y495800
X907086Y498487
X910432Y491044
Y493744
X913800Y495800
X913779Y498487
X917192Y491219
Y493919
X920700Y495944
Y498644
X923600Y491144
Y493744
X927165Y495944
Y498644
X929811Y490644
Y493244
X933632Y490644
X933647Y493344
Y495944
X933632Y498644
X938732Y490644
Y493344
Y495944
Y498644
X943897Y490444
X944000Y493100
X947443Y494944
Y497644
X950700Y490700
Y493300
X954000Y494700
Y497300
X961309Y499136
X973795Y499793
X976421Y499768
X976530Y497170
X1082800Y497650
X1084800Y499400
X1137992Y495887
Y498487
X1141038Y491144
X1140988Y493744
X1144385Y495887
Y498487
X1147331Y490894
Y493494
X1151168Y490867
Y493467
Y496167
Y498867
X1156252Y490867
Y493567
Y496167
Y498867
X1161320Y495800
X1161417Y498487
X1164363Y491044
Y493744
X1167500Y495800
X1167510Y498487
X1170656Y491144
Y493844
X1174203Y495787
Y498387
X1177849Y490944
X1177799Y493544
X1180400Y495787
Y498387
X1184142Y490794
Y493394
X1187978Y490609
Y493209
Y495909
Y498609
X1193063Y490909
Y493509
Y496209
Y498909
X1198100Y495800
Y498400
X1200974Y490744
Y493344
X1204400Y495887
Y498487
X1208267Y493444
Y496144
X1248474Y488913
X1249193Y491308
X1255388Y483557
X1256320Y490660
X1256350Y486080
X1257720Y493060
X1262843Y497553
X1266162Y496404
X1267584Y499694
X1269050Y486650
X1269006Y496016
X1269600Y480800
X1271105Y498516
X1271647Y482500
X1271662Y487326
X1277800Y497108
X1277978Y491571
X1280595Y496439
X1290500Y480200
Y482700
X1295240Y493359
X1297878Y493150
X1299450Y484950
X1309870Y499254
X1320300Y498300
X1334300Y499300
X1337100
X1341050Y498275
X1344761Y498282
X1360741Y486523
X1360863Y481673
X1362841Y492823
X1362880Y497556
X1363662Y486636
X1363800Y481600
X1365741Y492723
X1365719Y497545
X1366341Y481823
X1366309Y486618
X1368441Y492723
Y497523
X1380741Y487489
X1381041Y482575
X1383241Y498595
X1383263Y493673
X1383519Y487445
X1383600Y482504
X1386041Y493723
X1386033Y498811
X1386241Y482623
Y487323
X1388741Y493623
X1388719Y498745
X1412741Y494223
X1412941Y489523
X1413193Y482532
X1415541Y489523
X1415800Y495200
X1416100Y483500
X1418241Y489523
X1418341Y494423
X1418441Y482523
X1436441Y489323
X1436541Y494423
X1436600Y482900
X1439341Y489323
X1439400Y483600
Y494700
X1441842Y482924
X1442041Y489223
Y494423
X1447749Y485395
X1449568Y487276
X1452188Y487223
X1456602Y485864
X1456590Y488976
X1458060Y495020
X1460661Y484891
X1461267Y489790
X1470643Y495299
X1472250Y485100
X1473800Y495800
X1476800Y498900
X1482000Y481713
X1482300Y498900
X1482958Y486118
X1485300Y498962
X1487525Y487486
X1488500Y498900
X1489475Y484106
X1490100Y489700
X1493375Y484106
X1495325Y480726
Y487486
X1497275Y484106
X1499225Y480726
Y487486
X1501175Y484106
X1503125Y480726
X1505075Y484106
X1507025Y480726
Y487486
X1508975Y484106
X1509000Y498750
X1510925Y480726
Y487486
X1511752Y498780
X1512875Y484106
X1514825Y480726
Y487486
X1516775Y484106
X1518725Y480726
Y487486
X1522625
X1526525
X1526500Y498671
X1528475Y484106
X1531685Y499540
X1532375Y484106
X1534180Y498580
X1534325Y480726
Y487486
X1536275Y484106
X1538225Y480726
Y487486
X1540175Y484106
X1542125Y480726
Y487486
X1542475Y499400
X1544075Y484106
X1546025Y480726
Y487486
X1548300Y499000
X1549925Y487486
X1553825Y480726
Y487486
X1555510Y499475
X1555775Y484106
X1557725Y480726
X1565525
Y487486
X1567475Y484106
X1567817Y499735
X1568600Y494500
X1569425Y480726
X1570062Y487039
X1582644Y495077
X1587433Y490425
X1589025Y495975
X1592025
X1594880Y494880
X1597380Y495416
X1599900Y487100
X1600780Y495416
X1603500Y495300
X1603802Y487205
X1606200Y487100
X1614900Y498575
X1615100Y481400
X1615200Y489700
X1617600Y481400
X1617700Y489700
X1617771Y498714
X1621783Y498617
X1625485Y494188
X1629500Y491500
X1629530Y496374
X1639113Y496734
X1639271Y491135
X1640781Y487760
X1641963Y495964
X1642880Y490047
X1646700Y480300
X1651754Y488025
X1651926Y482197
X1651867Y484741
X1671050Y481000
Y483600
Y487000
Y490850
X1672159Y494042
X1672313Y497300
X1672606Y499820
X1676800Y483800
X1681500Y482000
X1687443Y487203
X1687500Y484000
X1689943Y487203
X1692443Y487259
X1694410Y499830
X1695658Y486945
X1698354Y486873
X1701617Y482706
X1705767Y482434
X1734000Y488100
X1736900Y487755
X1740400Y496300
X1741900Y487755
X1742900Y485000
X1743125Y496400
X1748125
X1748600Y485000
X1749300Y487855
X1749396Y493969
X1751868Y494045
X1753575Y496406
X1754300Y487855
X1755000Y485000
X1758500Y493800
X1758575Y496406
X1765325Y487355
Y490255
X1770325Y487355
Y490255
X1779303Y497246
X1784525Y488930
Y491830
X1784878Y496701
X1788045Y496654
X1789525Y488930
Y491830
X1791113Y496670
X1796125Y488930
Y491830
X1796400Y498000
X1801125Y488930
Y491830
X1803900Y491500
X1804000Y498176
X1806975Y488730
Y491630
X1811975Y488730
Y491630
X1812325Y481320
X1817325
X1819125Y488930
Y491830
X1824125Y488930
Y491830
X1830220Y479950
X1833700Y497300
X1836396Y481349
X1840500Y484650
Y487250
Y491500
Y494100
X1841900Y498800
X1843100Y491500
Y494100
X1847000Y487500
X1849795Y493379
X1850290Y486610
X1852719Y487575
Y492575
X1860000Y495500
X1863000Y480000
X1870138Y485732
X1875973Y499838
X1915100Y480050
X1919000Y487210
X1919230Y483430
X1928620Y482710
X1938300Y486250
X1938410Y490650
X1947380Y482450
X1947550Y485350
X1955790Y499790
X1968870Y481710
X1970500Y502720
X1968375Y509375
X1964270Y511410
X1959300Y518000
X1959260Y506010
X1957250Y512050
X1957100Y502990
X1956500Y507470
X1956300Y515900
X1952500Y508000
X1942328Y508712
X1937300Y508900
X1912800Y510700
X1909800
X1908300Y514500
X1873632Y500904
X1869914Y517225
X1866688Y517128
X1864339Y509560
X1859530Y516430
X1852340Y509140
X1844490Y509230
X1843000Y505000
X1842400Y516800
X1842450Y507520
X1834540Y519600
X1828200Y519000
X1828100Y516300
X1828000Y513200
X1825700Y514900
X1820400Y501100
X1815200Y501500
X1814852Y519901
X1810508Y515900
X1810200Y513300
X1809700Y506875
X1801600Y515600
X1798883Y515636
X1796153Y514200
X1776695Y512640
X1774200Y512800
X1750800Y516100
X1749090Y513790
X1738180Y503487
X1737300Y500900
X1733830Y502650
X1733639Y500085
X1729200Y519000
X1728700Y502600
X1728639Y500085
X1726600Y519000
X1722000Y513000
X1719560Y501770
X1716490Y506970
X1714530Y519900
X1713600Y513000
X1710594Y519900
X1709400Y513000
X1699900Y512300
X1692120Y501410
X1690091Y503995
X1687606Y500938
X1687500Y505200
X1684650
X1681650Y510673
X1650944Y505166
X1649545Y515215
X1649336Y511502
X1648330Y504544
X1645969Y514870
X1644651Y505500
X1642670Y514939
X1641470Y506403
X1639391Y513065
X1639394Y507798
X1629778Y507294
X1627068Y512626
X1627032Y510226
X1617300Y519000
X1615000Y510300
X1612500
X1568400Y503300
X1565210Y509160
X1565000Y506329
Y503329
X1564600Y500414
X1555832Y512288
X1555510Y501975
X1555438Y509717
Y507217
X1555424Y504609
X1548300Y511800
Y509200
Y506600
Y504000
Y501500
X1542475Y509600
Y507000
Y504400
Y501900
X1542425Y512200
X1534020Y511930
X1534039Y502906
X1533595Y509030
Y505530
X1531685Y502040
X1531580Y510790
X1526500Y506400
Y503800
Y501300
X1512400Y519020
X1511215Y507781
X1511126Y503038
X1510005Y518155
X1509585Y510645
X1508626Y503038
X1507405Y518155
X1506985Y510645
X1506060Y508180
X1505743Y516117
X1501934Y513047
X1501490Y504988
X1500877Y508239
X1500655Y516122
X1498277Y508239
X1498055Y516122
X1497267Y505323
X1496174Y514221
X1490929Y507104
X1488410Y517810
X1488293Y508000
X1485693
X1484200Y515700
X1483804Y509928
X1481975Y507975
X1481700Y515700
X1479375Y507975
X1476800Y507300
X1474400Y517200
X1472500Y509810
X1464553Y508872
X1461713Y515196
X1459213
X1458935Y512470
X1453700Y501600
X1407884Y512751
X1405950Y510650
X1402950
X1400445Y510159
X1396035Y514863
X1390330Y516690
X1388865Y519788
X1387568Y516892
X1386359Y519931
X1385033Y516848
X1383859Y519931
X1382578Y516805
X1381095Y519940
X1378609Y519931
X1377492Y516892
X1376109Y519931
X1373345Y519940
X1369757Y517465
X1355800Y508500
X1352590Y519170
X1352490Y515470
X1347081Y507919
X1346970Y519150
X1346870Y515450
X1344073Y508263
X1340986Y511187
X1339900Y518900
X1339600Y515800
X1335100Y507700
X1332600Y506300
X1332500Y509100
X1319075Y501000
X1316675Y500983
X1314272Y501000
X1313700Y517800
Y515200
X1311772Y501000
X1298460Y519450
Y516450
Y513450
X1298380Y510810
X1295960Y519450
Y516450
Y513450
X1295880Y510810
X1287770Y501897
X1278573Y519596
X1274576Y510235
X1271300Y510600
X1269209Y501777
X1269000Y514700
X1265157Y517999
Y510157
X1261811Y517999
Y510157
X1258464Y517999
Y510157
X1255120Y518000
Y510158
X1251771Y517999
Y510157
X1248425Y518057
Y510157
X1245078Y515814
Y513114
X1241732Y518157
Y510114
X1238385Y515814
Y513114
X1235039Y518157
Y510114
X1229874Y518114
Y515514
Y512914
X1229850Y510100
X1224750Y517900
X1224774Y515300
Y512700
Y510098
X1220953Y515814
Y513114
X1218307Y518157
X1218157Y510114
X1214874Y512774
X1211614Y518157
Y510114
X1208267Y515814
Y513114
X1204921Y518157
Y510114
X1201574Y515814
Y513114
X1198228Y518157
Y510114
X1193063Y518114
Y515514
Y512914
X1193039Y510100
X1187963Y515300
Y512700
Y510098
X1187939Y517900
X1184142Y515814
Y513114
X1181496Y518157
X1181346Y510114
X1177799Y515714
X1177849Y513114
X1174803Y518157
Y510114
X1171456Y515814
Y513114
X1168110Y518157
Y510114
X1164763Y515814
Y513114
X1161417Y518157
Y510114
X1156252Y518114
Y515514
Y512914
X1156228Y510100
X1151152Y515300
Y512700
Y510098
X1151128Y517900
X1147331Y515814
Y513114
X1144685Y518157
X1144535Y510114
X1140988Y515714
X1141038Y513114
X1137992Y518157
Y510114
X1134645Y515814
Y513114
X1131299Y518157
Y510114
X1127952Y515814
Y513114
X1124606Y518157
Y510114
X1119440Y518114
Y515514
Y512914
X1114316Y517900
X1114340Y515300
Y512700
Y510098
X1110520Y515714
Y513114
X1107874Y518157
X1107724Y510114
X1104177Y515714
X1104227Y513114
X1101181Y518157
Y510114
X1098300Y515300
X1097343Y512794
X1094488Y515364
Y510114
X1091141Y518057
Y512792
X1087795Y515364
Y510114
X1084448Y518157
Y512792
X1081102Y515364
Y509999
X1077755Y518157
Y512792
X1074409Y515364
Y510114
X1071062Y518157
X1067716Y515364
Y509999
X1064369Y518157
Y512792
X1061023Y515364
Y510114
X1057676Y518157
Y512792
X1054330Y515364
Y509999
X1050983Y518157
Y512792
X1047637Y515364
Y509999
X1044290Y512792
X1035750Y503006
X1034200Y506956
X1024800Y518856
Y516356
X1016473Y515152
Y510114
X1013873Y515152
Y510114
X1011250Y515200
X1011126Y510114
X1008650Y515200
X1008526Y510114
X1004134Y518157
X1003915Y512792
X1000787Y515364
X1000490Y509999
X997441Y518157
Y512792
X994094Y515364
Y510114
X990748Y518157
Y512792
X987401Y515364
Y509999
X984055Y518157
Y512792
X980708Y515364
Y510114
X977362Y518157
Y512792
X974015Y515364
Y509999
X970669Y518157
Y512792
X967322Y515364
Y510114
X963976Y518057
Y512792
X960629Y515364
Y510114
X957774Y512794
X957283Y518057
X953886Y515814
X953936Y513114
X950590Y518157
Y510114
X947243Y515814
Y513114
X943897Y518157
Y510114
X938732Y518114
Y515514
Y512914
X938708Y510100
X933608Y517900
X933632Y515300
Y512700
Y510098
X929811Y515814
Y513114
X927165Y518157
X927015Y510114
X923468Y515714
X923518Y513114
X920472Y518157
Y510114
X917125Y515814
Y513114
X913779Y518157
Y510114
X910432Y515814
Y513114
X907086Y518157
Y510114
X901921Y518114
Y515514
Y512914
X901897Y510100
X896797Y517900
X896821Y515300
Y512700
Y510098
X893000Y515814
Y513114
X890354Y518157
X890204Y510114
X886657Y515714
X886707Y513114
X883661Y518157
Y510114
X880314Y515814
Y513114
X876968Y518157
Y510114
X873621Y515814
Y513114
X870275Y518161
Y510114
X865110Y518114
Y515514
Y512914
X865086Y510100
X859986Y517900
X860010Y515300
Y512700
Y510098
X856189Y515814
Y513114
X853543Y518157
X853393Y510114
X849896Y513114
X849846Y515714
X846850Y518157
Y510114
X843503Y515814
Y513114
X840157Y518157
Y510114
X836810Y515814
Y513114
X833464Y518157
Y510114
X828299Y518114
Y515514
Y512914
X823175Y517900
X823199Y515300
Y512700
Y510098
X819378Y515764
Y513114
X816732Y518157
X816582Y510114
X813085Y513114
X813035Y515714
X810039Y518157
Y510114
X806692Y515814
Y513114
X803346Y518157
Y510114
X799999Y515814
Y513114
X796653Y518157
Y510114
X791488Y518114
Y515514
Y512914
X791464Y510100
X786364Y517900
X786388Y515300
Y512700
Y510098
X782567Y515814
Y513114
X779921Y518157
X779771Y510114
X776274Y513114
X776224Y515714
X773228Y518157
Y510114
X769881Y517900
X769500Y510100
X766535Y517900
X763950Y511040
Y508540
Y506040
X763706Y514250
X752900Y518621
X752496Y515974
X748524Y502174
X746024
X743524
X731600Y511600
X729000Y511500
X726040Y506080
X721894Y501346
X721414Y508986
X720565Y511338
X718546Y500283
X715900Y505650
X715009Y512917
X713200Y505500
X712100Y512700
X710643Y505496
X708500Y512500
X707850Y505700
X704500Y512850
X703800Y507100
X701500Y505500
X700500Y512850
X686200Y511700
X685050Y503970
X682050
X680000Y511800
X679049Y503746
X676600Y501300
X674000Y501200
X671500Y501300
X669300Y504000
X664610Y512810
X661500Y513900
X658900Y509300
X658500Y513900
X655000
X652000
X648025Y501575
X619392Y514700
X615549Y517999
Y510157
X612203Y517999
Y510157
X608856Y517999
Y510157
X605510Y517999
Y510157
X602163Y517999
Y510157
X598817Y518057
Y510157
X595470Y515814
Y513114
X592124Y518157
Y510114
X588777Y515814
Y513114
X585431Y518157
Y510114
X580266Y518114
Y515514
Y512914
X580242Y510100
X575166Y515300
Y512700
Y510098
X575142Y517900
X571345Y515814
Y513114
X568699Y518157
X568549Y510114
X565266Y512774
X562006Y518157
Y510114
X558659Y515814
Y513114
X555313Y518157
Y510114
X551966Y515814
Y513114
X548620Y518157
Y510114
X543455Y518114
Y515514
Y512914
X543431Y510100
X538355Y515300
Y512700
Y510098
X538331Y517900
X534534Y515814
Y513114
X531888Y518157
X531738Y510114
X528191Y515714
X528241Y513114
X525195Y518157
Y510114
X521848Y515814
Y513114
X518502Y518157
Y510114
X515155Y515814
Y513114
X511809Y518157
Y510114
X506644Y518114
Y515514
Y512914
X506620Y510100
X501520Y517900
X501544Y515300
Y512700
Y510098
X497723Y515814
Y513114
X495077Y518157
X494927Y510114
X491380Y515714
X491430Y513114
X488384Y518157
Y510114
X485037Y515814
Y513114
X481691Y518157
Y510114
X478344Y515814
Y513114
X474998Y518157
Y510114
X469832Y518114
Y515514
Y512914
X464708Y517900
X464732Y515300
Y512700
Y510098
X460912Y515714
Y513114
X458266Y518157
X458116Y510114
X454569Y515714
X454619Y513114
X451573Y518157
Y510114
X448692Y515300
X447735Y512794
X444880Y515364
Y510114
X441533Y518057
Y512792
X438187Y515364
Y510114
X434840Y518157
Y512792
X431494Y515364
Y509999
X428147Y518157
Y512792
X424801Y515364
Y510114
X421454Y518157
X418108Y515364
Y509999
X414761Y518157
Y512792
X411415Y515364
Y510114
X408068Y518157
Y512792
X404722Y515364
Y509999
X401375Y518157
Y512792
X398029Y515364
Y509999
X394682Y512792
X385244Y504027
X375192Y518856
Y516356
X366865Y515152
Y510114
X364265Y515152
Y510114
X361642Y515200
X361518Y510114
X359042Y515200
X358918Y510114
X354526Y518157
X354307Y512792
X351179Y515364
X350882Y509999
X347833Y518157
Y512792
X344486Y515364
Y510114
X341140Y518157
Y512792
X337793Y515364
Y509999
X334447Y518157
Y512792
X331100Y515364
Y510114
X327754Y518157
Y512792
X324407Y515364
Y509999
X321061Y518157
Y512792
X317714Y515364
Y510114
X314368Y518057
Y512792
X311021Y515364
Y510114
X308166Y512794
X307675Y518057
X304278Y515814
X304328Y513114
X300982Y518157
Y510114
X297635Y515814
Y513114
X294289Y518157
Y510114
X289124Y518114
Y515514
Y512914
X289100Y510100
X284000Y517900
X284024Y515300
Y512700
Y510098
X280203Y515814
Y513114
X277557Y518157
X277407Y510114
X273860Y515714
X273910Y513114
X270864Y518157
Y510114
X267517Y515814
Y513114
X264171Y518157
Y510114
X260824Y515814
Y513114
X257478Y518157
Y510114
X252313Y518114
Y515514
Y512914
X252289Y510100
X247189Y517900
X247213Y515300
Y512700
Y510098
X243392Y515814
Y513114
X240746Y518157
X240596Y510114
X237099Y513114
X237049Y515714
X234053Y518157
Y510114
X230706Y515814
Y513114
X227360Y518157
Y510114
X224013Y515814
Y513114
X220667Y518161
Y510114
X215502Y518114
Y515514
Y512914
X215478Y510100
X210378Y517900
X210402Y515300
Y512700
Y510098
X206581Y515814
Y513114
X203935Y518157
X203785Y510114
X200288Y513114
X200238Y515714
X197242Y518157
Y510114
X193895Y515814
Y513114
X190549Y518157
Y510114
X187202Y515814
Y513114
X183856Y518157
Y510114
X178691Y518114
Y515514
Y512914
X173567Y517900
X173591Y515300
Y512700
Y510098
X169770Y515764
Y513114
X167124Y518157
X166974Y510114
X163477Y513114
X163427Y515714
X160431Y518157
Y510114
X157084Y515814
Y513114
X153738Y518157
Y510114
X150391Y515814
Y513114
X147045Y518157
Y510114
X141880Y518114
Y515514
Y512914
X141856Y510100
X136756Y517900
X136780Y515300
Y512700
Y510098
X132959Y515814
Y513114
X130313Y518157
X130163Y510114
X126666Y513114
X126616Y515714
X123620Y518157
Y510114
X120273Y517900
X119892Y510100
X116927Y517900
X114442Y510300
Y507800
X105958Y518550
X86100Y505200
X79630Y504580
X79400Y502150
X76996Y504587
X77000Y502133
X74600Y502064
X74480Y504480
X66750Y519400
Y516900
X64600Y518100
Y515600
X60300Y508650
Y505450
Y502250
X57936Y519212
Y516012
X57100Y505450
Y502250
X55500Y519300
X53900Y505450
Y502250
X53000Y519300
X52992Y516846
X51607Y511747
X47550Y504367
X44050Y504383
X39200Y509500
X37600Y507400
X37000Y511200
X35707Y509055
X34300Y511000
X31800Y510600
X27280Y510420
X24400Y519500
X22491Y500618
X14700Y517000
X13600Y504300
X13300Y509600
X6748Y517021
X4000Y509500
X3354Y517143
X-2083Y513704
X-6200Y505400
X-6712Y515731
X-6676Y501800
X-7360Y512000
X-16186Y519304
X-16726Y503651
X-16766Y500106
X-17200Y510800
X-17302Y506798
X-18160Y522609
X-17300Y530800
X-14800Y526100
X-9600
X-9287Y531604
X-9291Y535201
X-5680Y524570
X-3100Y533991
X-2430Y524340
X280Y524350
X1040Y531218
X1439Y538083
X3600Y531300
X6200
X10932Y523601
X13639Y534683
Y537183
X15600Y539100
X17139Y534683
Y537183
X19100Y532300
X21700
X27000
X29400
X38389Y523748
X40111Y520623
X41500Y533800
X41993Y523425
X43241Y535965
X43505Y538714
X46400Y536290
Y539790
X46507Y523953
X47369Y527005
X49800Y524300
X53000Y521800
Y524300
X55500Y521800
Y524300
X58000Y521800
Y524300
X60000Y526500
X60700Y521900
X62500Y535500
X64380Y523606
Y526202
X64503Y521054
X65500Y535500
X66750Y521900
X66840Y524300
Y526800
X68500Y535500
X70521Y538403
X73009Y538444
X75461Y538468
X77960
X80389
X88855Y522359
X91650Y522000
X106392Y527413
Y537000
X114322Y525980
X114792Y528600
X119892Y536983
X120210Y529200
X123620Y528899
Y536999
X126580Y530949
Y534700
X130313Y528899
Y537049
X132959Y531100
Y534700
X136806Y529150
Y531750
X136780Y534399
Y536999
X141893Y528936
X141880Y531540
Y534149
X141906Y536750
X147045Y528899
Y537049
X150391Y530949
Y535100
X153738Y528899
Y537049
X157084Y530949
Y535100
X160431Y528899
Y536999
X163391Y530949
Y534700
X166974Y537049
X167124Y528899
X169770Y531100
Y534700
X173617Y529150
Y531750
X173591Y534399
Y536999
X178704Y528936
X178691Y531540
Y534149
X178717Y536750
X183856Y528899
Y537049
X187202Y530949
Y535100
X190549Y528899
Y537049
X193895Y530949
Y535100
X197242Y528899
Y536999
X200202Y530949
Y534700
X203935Y528899
Y537049
X206581Y531100
Y534700
X210428Y529150
Y531750
X210402Y534399
Y536999
X215515Y528936
X215502Y531540
Y534149
X215528Y536750
X220667Y528899
Y537049
X224013Y530949
Y535100
X227360Y528899
Y537049
X230706Y530949
Y535100
X234053Y528899
Y536999
X237013Y530949
Y534700
X240746Y528899
Y537049
X243392Y531100
Y534700
X247239Y531750
X247213Y534399
Y536999
X252326Y528936
X252313Y531540
Y534149
X252339Y536750
X257478Y528899
Y537049
X260824Y530949
Y535100
X264171Y528899
Y537049
X267517Y530949
Y535100
X270864Y528899
Y536999
X273824Y530949
Y534700
X277407Y537049
X277557Y528899
X280203Y531100
Y534700
X284050Y529150
Y531750
X284024Y534399
Y536999
X289137Y528936
X289124Y531540
Y534149
X289150Y536750
X294289Y528899
Y537049
X297635Y530949
Y535100
X300982Y528899
Y537049
X304328Y530949
Y535100
X307675Y536957
X307992Y533100
X311021Y529014
X314368Y536957
X317714Y529014
X321061Y536957
X321334Y533100
X327754Y529014
X331100Y536957
X334292Y533100
X337793Y529014
X341140Y536957
X347833Y529022
X351179Y536957
X357661Y531546
Y534000
X357872Y528942
X357910Y536727
X363760Y529293
X367692Y536200
X367911Y529057
X376785Y538305
X386630Y521860
X394587Y529026
X394595Y537058
X398029Y529007
Y536942
X408069Y529007
Y536942
X408184Y533100
X418108Y529007
Y536942
X421368Y533100
X424801Y536942
X431494
X434395Y532904
X441533Y529007
Y536957
X448410Y531156
X448432Y536723
X448557Y534061
X451573Y528899
Y536999
X454533Y530949
Y534700
X458266Y528899
Y537049
X460912Y531100
Y534700
X464732Y534399
Y536999
X464758Y529150
Y531750
X469845Y528936
X469832Y531540
Y534149
X469858Y536750
X474998Y528899
Y537049
X478344Y530949
Y535100
X481691Y528899
Y537049
X485037Y530949
Y535100
X488384Y528899
Y536999
X491344Y530949
Y534700
X495077Y528899
Y537049
X497723Y531100
Y534700
X501544Y534399
Y536999
X501570Y529150
Y531750
X506644Y531540
Y534149
X506657Y528936
X506670Y536750
X511809Y528899
Y537049
X515155Y530949
Y535100
X518502Y528899
Y537049
X521848Y530949
Y535100
X525195Y528899
Y536999
X528155Y530949
Y534700
X531888Y528899
Y537049
X534534Y531100
Y534700
X538381Y529150
Y531750
X538355Y534399
Y536999
X543468Y528936
X543455Y531540
Y534149
X543481Y536750
X548620Y528899
Y537049
X551966Y530949
Y535100
X555313Y528899
Y537049
X558659Y530949
Y535100
X562006Y528899
Y536999
X564966Y530949
Y534700
X568699Y528899
Y537049
X571345Y531100
Y534700
X575192Y529150
Y531750
X575166Y534399
Y536999
X580279Y528936
X580266Y531540
Y534149
X580292Y536750
X585431Y528899
Y537049
X588777Y530949
Y535100
X592124Y528899
Y537049
X595470Y530949
Y535100
X598817Y528899
Y537049
X602163Y528899
Y537057
X605510Y528899
Y537057
X608856Y528899
Y537057
X612203Y528899
Y537057
X615549Y528899
Y537057
X620192Y532978
X623600Y521700
X651150Y530200
X651100Y532700
X654150Y530200
X654200Y532800
X657250Y531300
Y534300
X659750Y531300
Y534300
X662640Y528330
X675500Y521900
X684500Y532900
X685200Y530500
X686375Y527778
X690500Y523300
X691900Y531350
Y534850
X697500Y531250
Y534750
X701200Y524250
X701255Y521538
X711704Y525483
X713600Y527700
Y530200
Y532700
X716100Y525200
Y527700
Y530200
Y532700
X716267Y522020
X725000Y533700
X728000Y533750
X732442Y529300
X732400Y531800
X732522Y524308
Y526808
X733500Y535200
Y537700
X734842Y529300
X734922Y526808
X734900Y531800
X736000Y535200
Y537700
X737400Y529400
X750518Y522108
X752900Y521121
X756000Y525950
Y537000
X763544Y522236
X764400Y528600
X765100Y537110
X769500Y536983
X769818Y529200
X773228Y528899
Y536999
X776188Y530949
Y534700
X779921Y528899
Y537049
X782567Y531100
Y534700
X786414Y529150
Y531750
X786388Y534399
Y536999
X791501Y528936
X791488Y531540
Y534149
X791514Y536750
X796653Y528899
Y537049
X799999Y530949
Y535100
X803346Y528899
Y537049
X806692Y530949
Y535100
X810039Y528899
Y536999
X812999Y530949
Y534700
X816582Y537049
X816732Y528899
X819378Y531100
Y534700
X823225Y529150
Y531750
X823199Y534399
Y536999
X828312Y528936
X828299Y531540
Y534149
X828325Y536750
X833464Y528899
Y537049
X836810Y530949
Y535100
X840157Y528899
Y537049
X843503Y530949
Y535100
X846850Y528899
Y536999
X849810Y530949
Y534700
X853543Y528899
Y537049
X856189Y531100
Y534700
X860036Y529150
Y531750
X860010Y534399
Y536999
X865123Y528936
X865110Y531540
Y534149
X865136Y536750
X870275Y528899
Y537049
X873621Y530949
Y535100
X876968Y528899
Y537049
X880314Y530949
Y535100
X883661Y528899
Y536999
X886621Y530949
Y534700
X890354Y528899
Y537049
X893000Y531100
Y534700
X896847Y531750
X896821Y534399
Y536999
X901934Y528936
X901921Y531540
Y534149
X901947Y536750
X907086Y528899
Y537049
X910432Y530949
Y535100
X913779Y528899
Y537049
X917125Y530949
Y535100
X920472Y528899
Y536999
X923432Y530949
Y534700
X927015Y537049
X927165Y528899
X929811Y531100
Y534700
X933632Y534399
Y536999
X933658Y529150
Y531750
X938745Y528936
X938732Y531540
Y534149
X938758Y536750
X943897Y528899
Y537049
X947243Y530949
Y535100
X950590Y528899
Y537049
X953936Y530949
Y535100
X957283Y536957
X957600Y533100
X960629Y529014
X963976Y536957
X967322Y529014
X970669Y536957
X970942Y533100
X977362Y529014
X980708Y536957
X983900Y533100
X987401Y529014
X990748Y536957
X997441Y529022
X1000787Y536957
X1007207Y531537
Y534137
X1007480Y528942
X1007518Y536727
X1013500Y529200
X1017300Y536200
X1017519Y529057
X1026500Y538500
X1035000Y521556
X1044195Y529026
X1044203Y537058
X1047637Y529007
Y536942
X1057677Y529007
Y536942
X1057792Y533100
X1067716Y529007
Y536942
X1070976Y533100
X1074409Y536942
X1081102
X1084003Y532904
X1091141Y529007
Y536942
X1098018Y531156
X1098040Y536723
X1098160Y533809
X1101181Y528899
Y536999
X1104141Y530949
Y534700
X1107874Y528899
Y537049
X1110520Y531100
Y534700
X1114340Y534399
Y536999
X1114366Y529150
Y531750
X1119440Y531540
Y534149
X1119453Y528936
X1119466Y536750
X1124606Y528899
Y537049
X1127952Y530949
Y535100
X1131299Y528899
Y537049
X1134645Y530949
Y535100
X1137992Y528899
Y536999
X1140952Y530949
Y534700
X1144685Y528899
Y537049
X1147331Y531100
Y534700
X1151178Y529150
Y531750
X1151152Y534399
Y536999
X1156265Y528936
X1156252Y531540
Y534149
X1156278Y536750
X1161417Y528899
Y537049
X1164763Y530949
Y535100
X1168110Y528899
Y537049
X1171456Y530949
Y535100
X1174803Y528899
Y536999
X1177763Y530949
Y534700
X1181496Y528899
Y537049
X1184142Y531100
Y534700
X1187989Y529150
Y531750
X1187963Y534399
Y536999
X1193076Y528936
X1193063Y531540
Y534149
X1193089Y536750
X1198228Y528899
Y537049
X1201574Y530949
Y535100
X1204921Y528899
Y537049
X1208267Y530949
Y535100
X1211614Y528899
Y536999
X1214574Y530949
Y534700
X1218307Y528899
Y537049
X1220953Y531100
Y534700
X1224800Y529150
Y531750
X1224774Y534399
Y536999
X1229887Y528936
X1229874Y531540
Y534149
X1229900Y536750
X1235039Y528899
Y537049
X1238385Y530949
Y535100
X1241732Y528899
Y537049
X1245078Y530949
Y535100
X1248425Y528899
Y537049
X1251771Y528899
Y537057
X1255120Y537034
X1258464Y528899
Y537057
X1261811Y528899
Y537057
X1265157Y528876
Y537057
X1269800Y532978
X1277200Y539100
X1295660Y527700
Y530700
Y533700
Y536700
X1298460Y527700
Y530700
Y533700
Y536700
X1318500Y539900
X1319300Y525450
Y527850
Y530250
Y532650
X1321800Y525450
Y527850
Y530250
Y532750
X1353520Y537480
X1356029Y537492
X1358529
X1361174Y537471
X1363674
X1366096Y539889
X1366265Y537437
X1368596Y539889
X1368765Y537437
X1371096Y539889
X1371265Y537437
X1375500Y537717
X1375621Y535254
X1378021Y535276
X1377979Y537717
X1380521Y535276
X1380479Y537717
X1384310Y535540
Y538540
X1386800Y535600
Y538500
X1388850Y522266
X1388900Y525230
X1390500Y539000
X1395242Y520301
X1395581Y525357
X1396158Y537595
X1399721Y537509
X1403027Y520231
X1408753Y527518
X1409500Y538000
X1410486Y529792
X1413600Y531300
X1414800Y521400
X1417800Y521500
X1419600Y531500
X1420200Y520500
X1420400Y538000
X1423800Y534800
X1426870Y530800
X1428500Y521000
X1428791Y535512
X1431690Y521530
X1436358Y525142
X1438390Y527175
X1439822Y537382
X1445750Y539000
X1451533Y527867
X1453533Y532667
X1458357Y523271
X1458629Y531604
X1461100Y523600
X1461500Y531500
X1473140Y525407
X1475316Y527194
X1478700Y533700
X1481200Y531200
X1481400Y539700
X1481700Y524200
X1483700Y531200
X1483900Y539700
X1484200Y524200
X1490100Y520000
X1492700
X1493930Y522800
X1494200Y530600
X1497106Y531368
X1503200Y530500
X1503400Y524663
X1505600Y530500
X1508772Y530416
X1511388Y531045
X1514118Y530411
X1581730Y537170
X1585155Y538574
X1620030Y525066
X1623551Y525015
X1626518Y528029
X1627407Y520318
X1627622Y524928
X1630159Y520608
X1631975Y527700
X1636848Y533794
X1637500Y529400
X1644800Y532800
X1667277Y535221
X1680133Y535489
X1681115Y525218
X1697261Y520192
X1699861
X1762715Y521085
X1766100Y521124
X1768900
X1780838Y522562
X1781300Y537800
X1783400Y522500
X1786000Y522600
X1789300Y520000
X1790250Y522350
X1794100Y521900
X1795200Y525700
X1798250Y529200
X1801200Y529800
X1803752Y529301
X1804500Y526200
X1806076Y523525
X1807752Y538501
X1807852Y533601
X1810350Y525650
X1812452Y533601
Y538501
X1813500Y526500
X1816584Y530542
X1816800Y525700
X1818509Y527893
X1825900Y523500
X1829000Y536315
X1831600Y529000
X1832500Y539500
X1834000Y534900
X1834100Y523900
X1836600Y521600
X1837000Y534900
X1837200Y525700
X1842500Y534500
X1842764Y528136
X1845407Y533178
X1847070Y537610
X1854530Y533132
X1860280Y520200
X1861080Y537090
X1864580Y537060
X1868110Y536000
X1877518Y527560
X1878000Y539000
X1878736Y533040
X1900250Y533700
X1905000Y533900
X1921244Y533750
X1940800Y537300
X1943300Y535700
X1948100Y538700
X1951900Y534900
X1955400Y530500
X1956606Y526671
X1958500Y535000
X1958940Y538890
X1963500Y521000
X1964890Y534940
X1967200Y521600
X1972800Y536800
X1972700Y552700
Y549950
X1963097Y551000
X1961715Y555639
X1959120Y547050
X1956191Y548700
X1953500Y551900
X1945900Y549900
X1939800Y546300
Y543700
X1939700Y540900
X1937800Y549700
X1937300Y541600
X1937200Y545100
X1935400Y550800
X1926600Y559500
X1923600Y554200
X1922500Y546700
X1922000Y543750
X1915050Y547900
X1914750Y544863
X1913800Y555500
X1911000Y556700
X1908400Y556800
X1907500Y545600
X1907200Y551600
X1899800Y548100
X1898850Y545250
X1897300Y548800
X1896899Y557790
X1896500Y555300
X1894299Y557790
X1878500Y553500
X1878450Y548650
X1873510Y541710
X1870250Y541950
X1869800Y557100
X1859708Y552708
X1859167Y559350
X1858528Y544528
X1858500Y540000
X1857812Y557245
X1857108Y552708
Y550108
X1855750Y548000
X1854508Y552708
X1852400Y554900
X1852250Y547900
X1848900Y548200
Y545500
X1848800Y551400
X1844100Y551000
X1840690Y557190
X1838000Y549700
X1835000Y550300
X1831800Y552300
X1831500Y548000
Y544500
X1828900Y552300
X1828824Y557663
X1828800Y546500
X1828700Y540252
X1816280Y553500
Y550400
X1816330Y545260
X1812952Y545501
X1811704Y554341
X1810052Y545103
X1809309Y555713
X1807600Y552047
X1806200Y549200
X1794000Y552800
X1793900Y550100
X1793320Y557968
X1786900Y552500
X1782300Y555900
X1781510Y546362
X1767500Y559800
X1767141Y555500
X1759500Y554500
X1757478Y548192
X1756500Y554500
X1754000Y553500
X1753807Y548183
X1749000Y552863
X1742200
X1738697Y557888
X1738498Y554255
X1738216Y548239
X1738088Y551000
X1733000Y557000
X1730759Y548162
X1708140Y547538
X1705348Y546633
X1700348
X1697839Y545759
X1686036Y548251
X1685000Y550544
X1680000
X1680007Y547917
X1677300Y550200
X1674600Y550544
X1669600
X1669121Y547923
X1664113Y548380
X1663754Y551000
X1658754
X1658466Y548380
X1638674Y556178
X1625094Y559200
Y555200
X1622040Y554827
X1609829Y556599
X1607533Y557644
X1510740Y557860
X1489380Y546030
X1461500Y540000
X1449922Y546664
X1447022Y546578
X1441252Y548631
X1439861Y540497
X1439123Y545294
X1438799Y542785
X1429026Y541026
X1428281Y546119
X1420500Y549800
X1412019Y557380
X1409519
X1407019
X1404519
X1401777Y557632
X1390595Y549328
X1390462Y541800
X1387907Y544286
X1386800Y541500
X1385033Y544267
X1384310Y541540
X1382331Y543818
X1380479Y540117
X1377979
X1376070Y559760
X1375479Y540117
X1366459Y550589
X1365028Y547954
X1363663Y540052
X1363568Y550589
X1362528Y547954
X1361600Y559400
X1361163Y540052
X1358518Y540073
X1356018
X1347700Y554100
X1344613Y558876
Y556376
Y553876
X1327956Y545655
X1324707Y545493
X1323500Y558400
Y555400
Y552400
X1320500Y558400
Y555400
Y552400
X1317500Y558400
Y555400
Y552400
X1316100Y543400
X1308500Y540784
X1305500Y542500
X1300000Y558400
Y555400
Y552400
X1279318Y545212
X1277137Y547393
X1268500Y555800
X1265157Y555799
Y547957
X1261811Y555799
Y547957
X1258464Y555799
Y547957
X1255120Y555144
X1251771Y555799
Y547957
X1248425Y555857
Y547957
X1245078Y553614
Y550914
X1241732Y555957
Y547914
X1238385Y553614
Y550914
X1235039Y555957
Y547914
X1229874Y555914
Y553314
Y550714
X1229850Y547900
X1224750Y555700
X1224774Y553100
Y550500
Y547898
X1220953Y553614
Y550914
X1218307Y555957
X1218157Y547914
X1214874Y550574
X1211614Y555957
Y547914
X1208267Y553614
Y550914
X1204921Y555957
Y547914
X1201574Y553614
Y550914
X1198228Y555957
Y547914
X1193063Y555914
Y553314
Y550714
X1193039Y547900
X1187963Y553100
Y550500
Y547898
X1187939Y555700
X1184142Y553614
Y550914
X1181496Y555957
X1181346Y547914
X1177799Y553514
X1177849Y550914
X1174803Y555957
Y547914
X1171456Y553614
Y550914
X1168110Y555957
Y547914
X1164763Y553614
Y550914
X1161417Y555957
Y547914
X1156252Y555914
Y553314
Y550714
X1156228Y547900
X1151152Y553100
Y550500
Y547898
X1151128Y555700
X1147331Y553614
Y550914
X1144685Y555957
X1144535Y547914
X1140988Y553514
X1141038Y550914
X1137992Y555957
Y547914
X1134645Y553614
Y550914
X1131299Y555957
Y547914
X1127952Y553614
Y550914
X1124606Y555957
Y547914
X1119440Y555914
Y553314
Y550714
X1119416Y547900
X1114316Y555700
X1114340Y553100
Y550500
Y547898
X1110520Y553514
Y550914
X1107874Y555957
X1107724Y547914
X1104177Y553514
X1104227Y550914
X1101181Y555957
Y547914
X1098300Y553100
X1098118Y549843
X1091141Y555842
Y547907
X1084450Y555857
X1083116Y552000
X1081102Y547907
X1077757Y555857
X1074409Y547907
X1070976Y552000
X1067716Y555842
X1061024Y555857
X1057792Y552000
X1057677Y547907
X1050984Y555842
X1047637Y547907
X1044290Y550592
X1026500Y546400
Y541000
X1026400Y543700
X1019800Y555800
X1017300Y547914
X1016819Y555842
X1014173
X1013873Y547914
X1011126
X1010928Y555842
X1007518
X1007280Y547914
X1007147Y553111
Y550511
X1000787Y547922
X997441Y555857
X990748Y547922
X987401Y555857
X983900Y552000
X980708Y547914
X977362Y555857
X970731Y552000
X970669Y547914
X967322Y555857
X963976Y547914
X960629Y555857
X957701Y552000
X957283Y548200
X953886Y553614
X953936Y550914
X950590Y555957
Y547914
X947243Y553614
Y550914
X943897Y555957
Y547914
X938732Y555914
Y553314
Y550714
X938708Y547900
X933608Y555700
X933632Y553100
Y550500
Y547898
X929811Y553614
Y550914
X927165Y555957
X927015Y547914
X923468Y553514
X923518Y550914
X920472Y555957
Y547914
X917125Y553614
Y550914
X913779Y555957
Y547914
X910432Y553614
Y550914
X907086Y555957
Y547914
X901921Y555914
Y553314
Y550714
X901897Y547900
X896797Y555700
X896821Y553100
Y550500
Y547898
X893000Y553614
Y550914
X890354Y555957
X890204Y547914
X886657Y553514
X886707Y550914
X883661Y555957
Y547914
X880314Y553614
Y550914
X876968Y555957
Y547914
X873621Y553614
Y550914
X870275Y555961
Y547914
X865110Y555914
Y553314
Y550714
X865086Y547900
X859986Y555700
X860010Y553100
Y550500
Y547898
X856189Y553614
Y550914
X853543Y555957
X853393Y547914
X849896Y550914
X849846Y553514
X846850Y555957
Y547914
X843503Y553614
Y550914
X840157Y555957
Y547914
X836810Y553614
Y550914
X833464Y555957
Y547914
X828299Y555914
Y553314
Y550714
X828275Y547900
X823175Y555700
X823199Y553100
Y550500
Y547898
X819378Y553564
Y550914
X816732Y555957
X816582Y547914
X813085Y550914
X813035Y553514
X810039Y555957
Y547914
X806692Y553614
Y550914
X803346Y555957
Y547914
X799999Y553614
Y550914
X796653Y555957
Y547914
X791488Y555914
Y553314
Y550714
X791464Y547900
X786364Y555700
X786388Y553100
Y550500
Y547898
X782567Y553614
Y550914
X779921Y555957
X779771Y547914
X776274Y550914
X776224Y553514
X773228Y555957
Y547914
X769881Y555700
X769500Y547900
X766535Y555700
X763677Y547783
X754910Y556400
X736300Y541500
X732098Y556000
Y553000
Y550000
X729550Y556000
Y553000
Y550000
X726200Y554750
Y551750
X723200Y554750
Y551750
X720200Y554750
Y551750
X715650Y551250
Y548250
Y545250
Y542250
X713650Y549750
Y546750
Y543750
Y540750
X709500Y555750
X708000Y553250
X706500Y555750
X705000Y553250
X703500Y555750
X702000Y553250
X700500Y555750
X699000Y553250
X696000
X660200Y552500
X657100
X653700
X650900
X646150Y546350
Y543350
Y540350
X618892Y555800
X615549Y555799
Y547957
X612203Y555799
Y547957
X608856Y555799
Y547957
X605510Y555799
Y547957
X602163Y555799
Y547957
X598817Y555857
Y547957
X595470Y553614
Y550914
X592124Y555957
Y547914
X588777Y553614
Y550914
X585431Y555957
Y547914
X580266Y555914
Y553314
Y550714
X580242Y547900
X575166Y553100
Y550500
Y547898
X575142Y555700
X571345Y553614
Y550914
X568699Y555957
X568549Y547914
X565266Y550574
X562006Y555957
Y547914
X558659Y553614
Y550914
X555313Y555957
Y547914
X551966Y553614
Y550914
X548620Y555957
Y547914
X543455Y555914
Y553314
Y550714
X543431Y547900
X538355Y553100
Y550500
Y547898
X538331Y555700
X534534Y553614
Y550914
X531888Y555957
X531738Y547914
X528191Y553514
X528241Y550914
X525195Y555957
Y547914
X521848Y553614
Y550914
X518502Y555957
Y547914
X515155Y553614
Y550914
X511809Y555957
Y547914
X506644Y555914
Y553314
Y550714
X506620Y547900
X501520Y555700
X501544Y553100
Y550500
Y547898
X497723Y553614
Y550914
X495077Y555957
X494927Y547914
X491380Y553514
X491430Y550914
X488384Y555957
Y547914
X485037Y553614
Y550914
X481691Y555957
Y547914
X478344Y553614
Y550914
X474998Y555957
Y547914
X469832Y555914
Y553314
Y550714
X469808Y547900
X464708Y555700
X464732Y553100
Y550500
Y547898
X460912Y553514
Y550914
X458266Y555957
X458116Y547914
X454569Y553514
X454619Y550914
X451573Y555957
Y547914
X448692Y553100
X448510Y549843
X441533Y555842
Y547907
X434842Y555857
X433508Y552000
X431494Y547907
X428149Y555857
X424801Y547907
X421368Y552000
X418108Y555842
Y547907
X411416Y555857
X408184Y552000
X408069Y547907
X401376Y555842
X398029Y547907
X394682Y550592
X376829Y546303
X376792Y543700
X370080Y555700
X367692Y547914
X367211Y555842
X364565
X364265Y547914
X361518
X361320Y555842
X357910
X357672Y547914
X357539Y553111
Y550511
X351179Y547922
X347833Y555857
X341140Y547922
X337793Y555857
X334292Y552000
X331100Y547914
X327754Y555857
X321123Y552000
X321061Y547914
X317714Y555857
X314368Y547914
X311021Y555857
X308100Y552000
X307675Y548200
X304278Y553614
X304328Y550914
X300982Y555957
Y547914
X297635Y553614
Y550914
X294289Y555957
Y547914
X289124Y555914
Y553314
Y550714
X289100Y547900
X284000Y555700
X284024Y553100
Y550500
Y547898
X280203Y553614
Y550914
X277557Y555957
X277407Y547914
X273860Y553514
X273910Y550914
X270864Y555957
Y547914
X267517Y553614
Y550914
X264171Y555957
Y547914
X260824Y553614
Y550914
X257478Y555957
Y547914
X252313Y555914
Y553314
Y550714
X252289Y547900
X247189Y555700
X247213Y553100
Y550500
Y547898
X243392Y553614
Y550914
X240746Y555957
X240596Y547914
X237099Y550914
X237049Y553514
X234053Y555957
Y547914
X230706Y553614
Y550914
X227360Y555957
Y547914
X224013Y553614
Y550914
X220667Y555961
Y547914
X215502Y555914
Y553314
Y550714
X215478Y547900
X210378Y555700
X210402Y553100
Y550500
Y547898
X206581Y553614
Y550914
X203935Y555957
X203785Y547914
X200288Y550914
X200238Y553514
X197242Y555957
Y547914
X193895Y553614
Y550914
X190549Y555957
Y547914
X187202Y553614
Y550914
X183856Y555957
Y547914
X178691Y555914
Y553314
Y550714
X178667Y547900
X173567Y555700
X173591Y553100
Y550500
Y547898
X169770Y553564
Y550914
X167124Y555957
X166974Y547914
X163477Y550914
X163427Y553514
X160431Y555957
Y547914
X157084Y553614
Y550914
X153738Y555957
Y547914
X150391Y553614
Y550914
X147045Y555957
Y547914
X141880Y555914
Y553314
Y550714
X141856Y547900
X136756Y555700
X136780Y553100
Y550500
Y547898
X132959Y553614
Y550914
X130313Y555957
X130163Y547914
X126666Y550914
X126616Y553514
X123620Y555957
Y547914
X120273Y555700
X119892Y547900
X116927Y555700
X115883Y548024
X105412Y556580
X81500Y557500
Y554500
X80389Y541468
X78500Y557500
Y554500
X77960Y541468
X75500Y557500
Y554500
X75461Y541468
X73009Y541444
X72500Y557500
Y554500
X70498Y541394
X69500Y557500
Y554500
X66500Y557500
Y554500
X63500Y557500
Y554500
X45880Y557820
Y554710
X38696Y557668
X35896
X33396
X29914Y557563
X27114
X17139Y553683
X17100Y545400
Y541200
X17035Y549558
X15787Y551700
X15800Y547500
Y543300
X1539Y550183
X1500Y543100
Y540600
X1400Y556500
X1439Y553783
Y546583
X-1200Y556500
X-4100Y554400
X-4300Y558400
X-8318Y542216
X-10200Y558200
X-10947Y544117
X-14971Y540000
X-17500Y574000
X-17397Y564242
X-12600Y578900
X-9283Y571324
X-8200Y578600
X-6566Y568363
X-2500Y569500
X0Y566800
X1439Y574083
X1500Y576600
Y579100
X3600Y567300
X6200
X15800Y575300
Y579500
X17139Y570683
Y573183
X17100Y577400
X19448Y566700
X21948
X24748
X46560Y577500
X63500Y561500
X66500
X69500
X71500Y575000
Y578000
X72500Y561500
X74500Y575000
Y578000
X75500Y561500
X78500
Y575000
Y578000
X81500Y561500
Y575000
Y578000
X105392Y566000
Y574800
X113692Y566000
X114509Y575658
X119892Y574700
X120092Y566900
X123620Y566699
Y574799
X126580Y568749
Y572500
X130313Y566699
Y574849
X132959Y568900
Y572500
X136806Y566950
Y569550
X136780Y572199
Y574799
X141893Y566736
X141880Y569340
Y571949
X141906Y574550
X147045Y566699
Y574849
X150391Y568749
Y572900
X153738Y566699
Y574849
X157084Y568749
Y572900
X160431Y566699
Y574799
X163391Y568749
Y572500
X166974Y574849
X167124Y566699
X169770Y568900
Y572500
X173617Y566950
Y569550
X173591Y572199
Y574799
X178704Y566736
X178691Y569340
Y571949
X178717Y574550
X183856Y566699
Y574849
X187202Y568749
Y572900
X190549Y566699
Y574849
X193895Y568749
Y572900
X197242Y566699
Y574799
X200202Y568749
Y572500
X203935Y566699
Y574849
X206581Y568900
Y572500
X210428Y566950
Y569550
X210402Y572199
Y574799
X215515Y566736
X215502Y569340
Y571949
X215528Y574550
X220667Y566699
Y574849
X224013Y568749
Y572900
X227360Y566699
Y574849
X230706Y568749
Y572900
X234053Y566699
Y574799
X237013Y568749
Y572500
X240746Y566699
Y574849
X243392Y568900
Y572500
X247239Y566950
Y569550
X247213Y572199
Y574799
X252326Y566736
X252313Y569340
Y571949
X252339Y574550
X257478Y566699
Y574849
X260824Y568749
Y572900
X264171Y566699
Y574849
X267517Y568749
Y572900
X270864Y566699
Y574799
X273824Y568749
Y572500
X277407Y574849
X277557Y566699
X280203Y568900
Y572500
X284050Y566950
Y569550
X284024Y572199
Y574799
X289137Y566736
X289124Y569340
Y571949
X289150Y574550
X294289Y566699
Y574849
X297635Y568749
Y572900
X300982Y566699
Y574849
X304328Y568749
Y572900
X307675Y574757
X307992Y570900
X311021Y566814
X314368Y574757
X317714Y566814
X321061Y574757
X321334Y570900
X327754Y566814
X331100Y574757
X334292Y570900
X337793Y566814
X341140Y574757
X347833Y566822
X351179Y574757
X357724Y569474
Y571973
X357910Y566814
X357872Y574742
X361218Y566814
Y574742
X364565Y566814
Y574742
X367192Y566814
Y574742
X376892Y577500
X394682Y569492
X398029Y566807
Y574742
X408069Y566807
Y574742
X408184Y570900
X418108Y566807
Y574742
X421368Y570900
X424801Y566807
Y574742
X431494Y566807
Y574742
X433508Y570900
X441533Y566807
Y574742
X448226Y569200
X448291Y574773
X451573Y566699
Y574799
X454533Y568749
Y572500
X458266Y566699
Y574849
X460912Y568900
Y572500
X464732Y572199
Y574799
X464758Y566950
Y569550
X469845Y566736
X469832Y569340
Y571949
X469858Y574550
X474998Y566699
Y574849
X478344Y568749
Y572900
X481691Y566699
Y574849
X485037Y568749
Y572900
X488384Y566699
Y574799
X491344Y568749
Y572500
X495077Y566699
Y574849
X497723Y568900
Y572500
X501544Y572199
Y574799
X501570Y566950
Y569550
X506644Y569340
Y571949
X506657Y566736
X506670Y574550
X511809Y566699
Y574849
X515155Y568749
Y572900
X518502Y566699
Y574849
X521848Y568749
Y572900
X525195Y566699
Y574799
X528155Y568749
Y572500
X531888Y566699
Y574849
X534534Y568900
Y572500
X538381Y566950
Y569550
X538355Y572199
Y574799
X543468Y566736
X543455Y569340
Y571949
X543481Y574550
X548620Y566699
Y574849
X551966Y568749
Y572900
X555313Y566699
Y574849
X558659Y568749
Y572900
X562006Y566699
Y574799
X564966Y568749
Y572500
X568699Y566699
Y574849
X571345Y568900
Y572500
X575192Y566950
Y569550
X575166Y572199
Y574799
X580279Y566736
X580266Y569340
Y571949
X580292Y574550
X585431Y566699
Y574849
X588777Y568749
Y572900
X592124Y566699
Y574849
X595470Y568749
Y572900
X598817Y566699
Y574849
X602163Y566699
Y574857
X605510Y566699
Y574857
X608856Y566699
Y574857
X612203Y566699
Y574857
X615549Y566699
Y574857
X618292Y574300
X644800Y563300
X647350Y568623
X647800Y563300
X649700Y574400
Y577000
X650050Y568623
X650800Y563300
X652140Y574511
Y577011
X653800Y563300
X658900Y569800
X660217Y576734
X661500Y569800
X663100Y574200
X665700
X669099Y573493
X671599
X674099
X680029Y577503
X689193Y573493
X690100Y575860
X693200Y575900
X702000Y571400
X702100Y568800
X712600Y571900
X716300Y569400
X722200Y571300
X727400
X732600Y573950
X755000Y566000
Y574800
X763300Y566000
X764117Y575658
X769500Y574700
X769700Y566900
X773228Y566699
Y574799
X776188Y568749
Y572500
X779921Y566699
Y574849
X782567Y568900
Y572500
X786414Y566950
Y569550
X786388Y572199
Y574799
X791501Y566736
X791488Y569340
Y571949
X791514Y574550
X796653Y566699
Y574849
X799999Y568749
Y572900
X803346Y566699
Y574849
X806692Y568749
Y572900
X810039Y566699
Y574799
X812999Y568749
Y572500
X816582Y574849
X816732Y566699
X819378Y568900
Y572500
X823225Y566950
Y569550
X823199Y572199
Y574799
X828312Y566736
X828299Y569340
Y571949
X828325Y574550
X833464Y566699
Y574849
X836810Y568749
Y572900
X840157Y566699
Y574849
X843503Y568749
Y572900
X846850Y566699
Y574799
X849810Y568749
Y572500
X853543Y566699
Y574849
X856189Y568900
Y572500
X860036Y566950
Y569550
X860010Y572199
Y574799
X865123Y566736
X865110Y569340
Y571949
X865136Y574550
X870275Y566699
Y574849
X873621Y568749
Y572900
X876968Y566699
Y574849
X880314Y568749
Y572900
X883661Y566699
Y574799
X886621Y568749
Y572500
X890354Y566699
Y574849
X893000Y568900
Y572500
X896847Y566950
Y569550
X896821Y572199
Y574799
X901934Y566736
X901921Y569340
Y571949
X901947Y574550
X907086Y566699
Y574849
X910432Y568749
Y572900
X913779Y566699
Y574849
X917125Y568749
Y572900
X920472Y566699
Y574799
X923432Y568749
Y572500
X927015Y574849
X927165Y566699
X929811Y568900
Y572500
X933632Y572199
Y574799
X933658Y566950
Y569550
X938745Y566736
X938732Y569340
Y571949
X938758Y574550
X943897Y566699
Y574849
X947243Y568749
Y572900
X950590Y566699
Y574849
X953936Y568749
Y572900
X957283Y574757
X957600Y570900
X960629Y566814
X963976Y574757
X967322Y566814
X970669Y574757
X970942Y570900
X977362Y566814
X980708Y574757
X983900Y570900
X987401Y566814
X990748Y574757
X997441Y566822
X1000787Y574757
X1007332Y569410
Y572010
X1007518Y566814
X1007480Y574742
X1010826Y566814
Y574742
X1014173Y566814
Y574742
X1016800Y566814
Y574742
X1026500Y577500
X1044290Y569492
X1047637Y566807
Y574742
X1057677Y566807
Y574742
X1057792Y570900
X1067716Y566807
Y574742
X1070976Y570900
X1074409Y566807
Y574742
X1081102Y566807
Y574742
X1083116Y570900
X1091141Y566807
Y574742
X1097834Y569200
X1097899Y574773
X1101181Y566699
Y574799
X1104141Y568749
Y572500
X1107874Y566699
Y574849
X1110520Y568900
Y572500
X1114340Y572199
Y574799
X1114366Y566950
Y569550
X1119440Y569340
Y571949
X1119453Y566736
X1119466Y574550
X1124606Y566699
Y574849
X1127952Y568749
Y572900
X1131299Y566699
Y574849
X1134645Y568749
Y572900
X1137992Y566699
Y574799
X1140952Y568749
Y572500
X1144685Y566699
Y574849
X1147331Y568900
Y572500
X1151178Y566950
Y569550
X1151152Y572199
Y574799
X1156265Y566736
X1156252Y569340
Y571949
X1156278Y574550
X1161417Y566699
Y574849
X1164763Y568749
Y572900
X1168110Y566699
Y574849
X1171456Y568749
Y572900
X1174803Y566699
Y574799
X1177763Y568749
Y572500
X1181496Y566699
Y574849
X1184142Y568900
Y572500
X1187989Y566950
Y569550
X1187963Y572199
Y574799
X1193076Y566736
X1193063Y569340
Y571949
X1193089Y574550
X1198228Y566699
Y574849
X1201574Y568749
Y572900
X1204921Y566699
Y574849
X1208267Y568749
Y572900
X1211614Y566699
Y574799
X1214574Y568749
Y572500
X1218307Y566699
Y574849
X1220953Y568900
Y572500
X1224800Y566950
Y569550
X1224774Y572199
Y574799
X1229887Y566736
X1229874Y569340
Y571949
X1229900Y574550
X1235039Y566699
Y574849
X1238385Y568749
Y572900
X1241732Y566699
Y574849
X1245078Y568749
Y572900
X1248425Y566699
Y574849
X1251771Y566699
Y574857
X1255120Y574834
X1258464Y566699
Y574857
X1261811Y566699
Y574857
X1265157Y566676
Y574857
X1267900Y574300
X1285400Y561000
X1288100Y562000
X1290292Y578962
X1290900Y563300
X1292190Y576952
X1295090Y579360
X1303000Y563400
Y565900
Y568900
Y571400
Y576000
Y579000
X1306000Y563400
Y565900
Y568900
Y571400
Y576000
Y579000
X1309000Y563400
Y565900
Y568900
Y571400
X1312000Y563400
Y565900
Y568900
Y571400
X1315000Y563400
Y565900
Y568900
Y571400
X1318000Y563400
Y565900
Y568900
Y571400
X1321000Y563400
Y565900
Y568900
Y571400
X1323774Y563145
Y566145
X1324000Y568900
Y571400
X1333026Y563337
Y566237
X1335526Y563337
Y566237
X1338026Y563337
X1338000Y566300
X1340526Y563337
X1340700Y566300
X1343026Y563337
X1343100Y566300
X1344613Y561376
X1355548Y559959
X1358439
X1360247Y567390
X1360261Y562373
Y578873
X1360500Y570900
Y574700
X1362000Y565600
Y572800
Y576700
X1362100Y569100
X1375961Y562273
X1376000Y565700
X1375961Y569473
X1376000Y572956
Y575456
X1375961Y577973
X1379000Y561500
X1382032Y560143
X1382200Y562700
X1382500Y575400
Y579100
X1385316Y574705
X1387986Y574960
X1390623Y574986
X1400216Y560128
X1400288Y570099
X1400830Y564090
X1404420Y576330
X1404519Y560280
X1406993Y560343
X1409693
X1410340Y570370
X1410850Y564210
X1412093Y560343
X1414744Y570801
X1414743Y573363
X1414800Y579800
X1414851Y576624
X1415582Y562904
X1417182Y570711
X1417252Y573470
X1417288Y576624
X1418402Y562624
X1419809Y570723
Y573723
Y576723
X1421560Y563455
X1422509Y570823
Y573823
Y576823
X1422500Y579800
X1425243Y562260
X1432560Y561160
X1436160Y561200
X1441409Y561117
X1441805Y570887
X1443797Y572482
X1445800Y574300
X1447852Y575687
X1451150Y569900
Y573200
X1465700Y570500
X1468101Y573963
X1468649Y570012
X1474776Y572315
X1477493
X1479893
X1482293
X1484693
X1487093
X1489493
X1491776Y573571
X1494422Y574000
X1496900
X1499900
X1518000Y562330
X1523416Y573949
X1525500Y577684
X1525837Y574700
X1527698Y578870
X1527822Y576130
X1529944Y574725
X1529894Y577342
X1529942Y579853
X1532354Y577283
X1532642Y579853
X1558800Y563900
X1561300Y564000
X1563448Y566766
X1563432Y569340
X1563800Y564100
X1565600Y565700
Y568100
X1565800Y570600
X1565940Y573120
X1566000Y575820
X1580300Y560500
Y563000
X1580360Y565524
X1580400Y568000
X1587610Y579550
X1596570Y562266
X1596620Y564764
X1596600Y567250
X1599070Y562266
X1599120Y564764
X1599170Y572780
X1601825Y568325
Y572325
X1602000Y565700
X1603120Y578020
X1605994Y578500
X1607533Y561644
X1610080Y561367
X1624293Y561747
X1652500Y575600
X1652669Y578350
X1653960Y562930
X1699600Y578100
X1710389Y577787
X1722500Y562000
X1725694Y568814
Y571814
X1730814Y568814
X1733000Y560000
X1733368Y579868
X1737958Y560500
X1743000Y570000
Y574500
X1743100Y561700
X1743200Y567300
X1743500Y564500
X1746000Y574000
X1754897Y578750
X1756417Y563840
X1762595Y576191
X1764300Y570900
X1765300Y574700
X1767000Y563500
X1767529Y566200
X1767455Y571695
X1769000Y576378
X1770719Y573964
X1772578Y575993
X1779500Y579500
X1780394Y561076
X1780500Y568000
Y570718
X1781000Y565000
X1783700Y576400
Y579200
X1786500Y562200
X1792100Y566900
X1792805Y574675
X1793100Y578500
X1793660Y560570
X1794000Y568800
X1807958Y565690
X1808057Y570125
Y573125
X1810385Y568821
X1810387Y571435
X1810863Y560637
X1812802Y578693
X1816020Y571448
X1816100Y576200
X1816175Y567669
X1828700Y569474
X1828800Y575600
X1828875Y563674
X1829300Y572900
X1832200Y567760
X1837475Y573835
X1837534Y579322
X1840700Y563800
X1856573Y576534
X1858000Y574000
X1858681Y568087
X1870100Y561150
X1874825Y564125
X1875850Y567200
X1878875Y565475
X1879800Y579000
X1882300Y565550
X1900729Y569557
X1906050Y569100
X1915593Y576807
X1923000Y568700
X1923500Y579500
X1923600Y565100
Y572300
Y575500
X1932800Y564300
X1934200Y573700
Y577700
X1934400Y569400
X1934600Y561900
X1936900Y568000
X1937250Y578200
X1961500Y561700
X1962500Y578500
X1962950Y566600
X1963000Y573000
X1972700Y576400
X1972800Y565200
X1973000Y597200
X1961771Y591744
X1961500Y582700
X1938000Y597320
X1937870Y594480
X1935400Y583000
X1932390Y590100
X1923504Y592500
X1923400Y583000
X1921800Y586100
X1918880Y586460
X1914700Y594600
X1911750Y592800
X1896358Y595255
X1895523Y586365
X1889800Y580200
X1885100Y584300
X1879862Y581862
X1875600Y588500
X1870892Y583245
X1868200Y590939
X1866800Y588000
X1858000Y586250
X1856040Y588704
X1848900Y590750
X1845000Y590800
X1844018Y586482
X1839126Y583354
X1838224Y586650
X1836281Y589122
X1829176Y584287
X1829051Y591299
X1825014Y593695
X1822273Y595046
X1819654Y593803
X1816458Y587480
X1816052Y584101
X1813456Y583500
X1812852Y596401
Y591601
X1811100Y586800
X1809600Y582800
X1808252Y596401
X1808152Y591601
X1806200Y582900
X1800352Y596101
X1800378Y593527
X1795000Y599600
X1793452Y586701
X1792170Y583900
X1791323Y594030
X1791349Y589122
X1788300Y585100
X1787500Y597791
X1785050Y584550
X1784200Y593924
X1779400Y582500
X1779000Y598900
Y588500
Y585500
X1778675Y592224
X1766400Y599400
X1763500Y599100
X1762062Y592055
Y589555
X1756578Y586743
X1742509Y595869
X1742381Y591530
Y588530
Y585530
X1740270Y594419
X1739500Y586500
X1739211Y596711
X1739179Y592070
X1738434Y588986
X1736003Y588244
X1732443Y597142
Y592342
X1730774Y579960
X1728245Y585244
X1727843Y597142
X1727743Y592342
X1724899Y584748
X1724250Y588250
X1718037Y597184
Y594684
X1718008Y592002
X1718000Y587723
X1710000Y595500
X1709950Y592900
X1709183Y588700
X1698600Y584800
X1662580Y593200
X1661880Y583900
X1660680Y590750
Y586750
X1652700Y591300
X1652669Y582350
X1652499Y597950
Y593950
X1649900Y583500
X1622330Y592325
X1615030Y584260
X1614700Y597000
X1613721Y592325
X1613349Y599250
X1612519Y590004
Y586004
X1605994Y582500
X1603919Y596750
Y592750
X1603060Y582920
X1601504Y591526
X1601540Y588793
X1601270Y597200
X1592934Y592396
X1590304Y596896
X1589604Y590196
Y585896
X1587679Y596867
X1585179Y596902
X1581704Y590196
Y585896
X1572950Y593950
X1565389Y585721
X1564300Y599400
X1558800Y599300
X1555600Y591100
X1554400Y599300
X1554358Y587258
X1553000Y591100
X1550990Y586588
X1545407Y598393
X1545200Y585724
X1545000Y591100
X1542600Y585724
X1535565Y591658
X1534968Y597268
X1532400Y582300
X1529600
X1526950Y597300
X1525500Y582674
Y580184
X1524800Y598778
X1522900Y597300
X1520813Y598508
X1518800Y597200
X1516800Y598639
X1514500Y597300
X1512500Y598639
X1510450Y597300
X1508031Y599922
X1507950Y597300
X1491412Y596032
X1489229Y597571
X1487329Y596032
X1485429Y597571
X1483104Y596072
X1481229Y597571
X1479029Y596132
X1477129Y597656
X1474912Y599532
Y596032
X1472412Y599532
Y596032
X1470353Y592128
X1469767Y596353
X1469701Y599554
X1462155Y592761
X1462039Y590354
X1461930Y587956
X1461878Y585556
X1461707Y583162
X1461653Y580762
X1443654Y594749
X1443473Y599944
X1442525Y597279
X1433100Y581770
X1432590Y584550
X1430570Y580890
X1427500Y581100
X1422920Y586250
X1420420
X1417920
X1415173Y586332
X1412673
X1410950Y589670
X1400980Y589586
Y587086
X1398010Y590040
X1397980Y587086
X1395060Y590630
X1392500Y592000
X1383074Y581963
X1382100Y592800
X1382000Y589500
X1379053Y581864
X1376800Y584328
X1375961Y593473
X1375861Y597073
X1375600Y589700
X1373700Y584656
X1371100
X1364426Y586637
Y584137
X1363761Y581373
X1361926Y586537
Y584037
X1361600Y599900
X1361500Y595700
X1360261Y593573
Y581373
X1360200Y597800
X1360226Y591037
X1360100Y588400
X1359100Y586200
X1357726Y591037
X1357400Y588400
X1324200Y597600
X1321100Y598500
X1318100
X1315100
X1312100
X1309100
X1298100Y598300
Y595800
Y592500
Y590000
X1293290Y581160
X1282600Y583600
Y581000
X1273200Y582200
X1270400Y593600
X1267800
X1265157Y593599
Y585757
X1261811Y593599
Y585757
X1258464Y593599
Y585757
X1255120Y593600
X1251771Y593599
Y585757
X1248425Y593657
Y585757
X1245078Y591414
Y588714
X1241732Y593757
Y585714
X1238385Y591414
Y588714
X1235039Y593757
Y585714
X1229874Y593714
Y591114
Y588514
X1229850Y585700
X1224750Y593500
X1224774Y590900
Y588300
Y585698
X1220953Y591414
Y588714
X1218307Y593757
X1218157Y585714
X1214660Y588714
X1211614Y593757
Y585714
X1208267Y591414
Y588714
X1204921Y593757
Y585714
X1201574Y591414
Y588714
X1198228Y593757
Y585714
X1193063Y593714
Y591114
Y588514
X1193039Y585700
X1187963Y590900
Y588300
Y585698
X1187939Y593500
X1184142Y591414
Y588714
X1181496Y593757
X1181346Y585714
X1177799Y591314
X1177849Y588714
X1174803Y593757
Y585714
X1171456Y591414
Y588714
X1168110Y593757
Y585714
X1164763Y591414
Y588714
X1161417Y593757
Y585714
X1156252Y593714
Y591114
Y588514
X1156228Y585700
X1151152Y590900
Y588300
Y585698
X1151128Y593500
X1147331Y591414
Y588714
X1144685Y593757
X1144535Y585714
X1140988Y591314
X1141038Y588714
X1137992Y593757
Y585714
X1134645Y591414
Y588714
X1131299Y593757
Y585714
X1127952Y591414
Y588714
X1124606Y593757
Y585714
X1119440Y593714
Y591114
Y588514
X1119416Y585700
X1114316Y593500
X1114340Y590900
Y588300
Y585698
X1110520Y591314
Y588714
X1107874Y593757
X1107724Y585714
X1104177Y591314
X1104227Y588714
X1101181Y593757
Y585714
X1098300Y590900
X1097343Y588394
X1091141Y593642
Y585707
X1084450Y593657
X1083108Y589800
X1081102Y585707
X1077757Y593657
X1074409Y593642
Y585707
X1070242Y589800
X1067716Y593642
Y585599
X1061024Y593657
X1057792Y589800
X1057677Y585707
X1050984Y593642
X1047637Y585707
X1044290Y588392
X1026500Y581000
X1025450Y593650
X1022950
X1020300Y593700
X1019277Y585714
X1017519Y593642
X1016473Y585714
X1014919Y593642
X1013873Y585714
X1011572Y593642
X1011126Y585714
X1006634Y593642
X1006633Y585714
X1006406Y590966
Y588366
X1000787Y585722
X997441Y593657
X990748Y585722
X987401Y593657
X983900Y589800
X980708Y585714
X977362Y593657
X970731Y589800
X970669Y585714
X967322Y593657
X963976Y585714
X960629Y593657
X957500Y591000
X957456Y588334
X953886Y591414
X953936Y588714
X950590Y593757
Y585714
X947243Y591414
Y588714
X943897Y593757
Y585714
X938732Y593714
Y591114
Y588514
X938708Y585700
X933608Y593500
X933632Y590900
Y588300
Y585698
X929811Y591414
Y588714
X927165Y593757
X927015Y585714
X923468Y591314
X923518Y588714
X920472Y593757
Y585714
X917125Y591414
Y588714
X913779Y593757
Y585714
X910432Y591414
Y588714
X907086Y593757
Y585714
X901921Y593714
Y591114
Y588514
X901897Y585700
X896797Y593500
X896821Y590900
Y588300
Y585698
X893000Y591414
Y588714
X890354Y593757
X890204Y585714
X886657Y591314
X886707Y588714
X883661Y593757
Y585714
X880314Y591414
Y588714
X876968Y593757
Y585714
X873621Y591414
Y588714
X870275Y593761
Y585714
X865110Y593714
Y591114
Y588514
X865086Y585700
X859986Y593500
X860010Y590900
Y588300
Y585698
X856189Y591414
Y588714
X853543Y593757
X853393Y585714
X849896Y588714
X849846Y591314
X846850Y593757
Y585714
X843503Y591414
Y588714
X840157Y593757
Y585714
X836810Y591414
Y588714
X833464Y593757
Y585714
X828299Y593714
Y591114
Y588514
X828275Y585700
X823175Y593500
X823199Y590900
Y588300
Y585698
X819378Y591364
Y588714
X816732Y593757
X816582Y585714
X813085Y588714
X813035Y591314
X810039Y593757
Y585714
X806692Y591414
Y588714
X803346Y593757
Y585714
X799999Y591414
Y588714
X796653Y593757
Y585714
X791488Y593714
Y591114
Y588514
X791464Y585700
X786364Y593500
X786388Y590900
Y588300
Y585698
X782567Y591414
Y588714
X779921Y593757
X779771Y585714
X776274Y588714
X776224Y591314
X773228Y593757
Y585714
X769500Y585700
X766600Y590700
X766535Y593500
X765900Y587300
X763450Y585200
X755900Y593650
X753300Y593600
X752500Y585150
X739307Y598850
X727106Y586550
X725400Y580900
X725173Y598171
X722500Y580900
X722406Y598950
X718200Y581000
X717612Y598554
X712000Y599500
Y597000
X708900Y589850
X708800Y599300
Y596700
X707500Y587800
X706100Y589850
X696600Y581400
X693126Y581380
X680910Y582000
X674200Y588900
X671791Y588920
X668891Y588900
X665000Y598500
X662000Y589000
X660230Y598170
X653100Y587000
X651750Y584150
X648180Y590702
X646760Y592992
X644500Y594400
X618192Y593600
X615549Y593599
Y585757
X612203Y593599
Y585757
X608856Y593599
Y585757
X605510Y593599
Y585757
X602163Y593599
Y585757
X598817Y593657
Y585757
X595470Y591414
Y588714
X592124Y593757
Y585714
X588777Y591414
Y588714
X585431Y593757
Y585714
X580266Y593714
Y591114
Y588514
X580242Y585700
X575166Y590900
Y588300
Y585698
X575142Y593500
X571345Y591414
Y588714
X568699Y593757
X568549Y585714
X565052Y588714
X562006Y593757
Y585714
X558659Y591414
Y588714
X555313Y593757
Y585714
X551966Y591414
Y588714
X548620Y593757
Y585714
X543455Y593714
Y591114
Y588514
X543431Y585700
X538355Y590900
Y588300
Y585698
X538331Y593500
X534534Y591414
Y588714
X531888Y593757
X531738Y585714
X528191Y591314
X528241Y588714
X525195Y593757
Y585714
X521848Y591414
Y588714
X518502Y593757
Y585714
X515155Y591414
Y588714
X511809Y593757
Y585714
X506644Y593714
Y591114
Y588514
X506620Y585700
X501520Y593500
X501544Y590900
Y588300
Y585698
X497723Y591414
Y588714
X495077Y593757
X494927Y585714
X491380Y591314
X491430Y588714
X488384Y593757
Y585714
X486250Y591020
X485037Y588714
X481691Y593757
Y585714
X478344Y591414
Y588714
X474998Y593757
Y585714
X469832Y593714
Y591114
Y588514
X469808Y585700
X464708Y593500
X464732Y590900
Y588300
Y585698
X460912Y591314
Y588714
X458266Y593757
X458116Y585714
X454569Y591314
X454619Y588714
X451573Y593757
Y585714
X448692Y590900
X447735Y588394
X441533Y593642
Y585707
X434842Y593657
X433500Y589800
X431494Y585707
X428149Y593657
X424801Y585707
X420634Y589800
X418108Y593642
Y585599
X411416Y593657
X408184Y589800
X408069Y585707
X401376Y593642
X398029Y585707
X394682Y588392
X376892Y581127
X376204Y593650
X373400Y593800
X370659Y593691
X370596Y585614
X367911Y593642
X366890Y586000
X365311Y593642
X364265Y585714
X361964Y593642
X361518Y585714
X357026Y593642
X357025Y585714
X356798Y590939
Y588366
X351179Y585722
X347833Y593657
X341140Y585722
X337793Y593657
X334292Y589800
X331100Y585714
X327754Y593657
X321192Y589800
X321061Y585714
X317714Y593657
X314368Y585714
X311021Y593657
X307892Y591000
X307848Y588334
X304278Y591414
X304328Y588714
X300982Y593757
Y585714
X297635Y591414
Y588714
X294289Y593757
Y585714
X289124Y593714
Y591114
Y588514
X289100Y585700
X284000Y593500
X284024Y590900
Y588300
Y585698
X280203Y591414
Y588714
X277557Y593757
X277407Y585714
X273860Y591314
X273910Y588714
X270864Y593757
Y585714
X267517Y591414
Y588714
X264171Y593757
Y585714
X260824Y591414
Y588714
X257478Y593757
Y585714
X252313Y593714
Y591114
Y588514
X252289Y585700
X247189Y593500
X247213Y590900
Y588300
Y585698
X243392Y591414
Y588714
X240746Y593757
X240596Y585714
X237099Y588714
X237049Y591314
X234053Y593757
Y585714
X230706Y591414
Y588714
X227360Y593757
Y585714
X224013Y591414
Y588714
X220667Y593761
Y585714
X215502Y593714
Y591114
Y588514
X215478Y585700
X210378Y593500
X210402Y590900
Y588300
Y585698
X206581Y591414
Y588714
X203935Y593757
X203785Y585714
X200288Y588714
X200238Y591314
X197242Y593757
Y585714
X193895Y591414
Y588714
X190549Y593757
Y585714
X187202Y591414
Y588714
X183856Y593757
Y585714
X178691Y593714
Y591114
Y588514
X178667Y585700
X173567Y593500
X173591Y590900
Y588300
Y585698
X169770Y591364
Y588714
X167124Y593757
X166974Y585714
X163477Y588714
X163427Y591314
X160431Y593757
Y585714
X157084Y591414
Y588714
X153738Y593757
Y585714
X150391Y591414
Y588714
X147045Y593757
Y585714
X141880Y593714
Y591114
Y588514
X141856Y585700
X136756Y593500
X136780Y590900
Y588300
Y585698
X132959Y591414
Y588714
X130313Y593757
X130163Y585714
X126666Y588714
X126616Y591314
X123620Y593757
Y585714
X119892Y585700
X116992Y590700
X116927Y593500
X114150Y585850
X105352Y594770
X81500Y599000
Y596000
Y582000
X78500Y599000
Y596000
Y582000
X75500Y599000
Y596000
X74500Y582000
X72500Y599000
Y596000
X71500Y582000
X69500Y599000
Y596000
X66500Y599000
Y596000
X63500Y599000
Y596000
X46560Y581000
X46500Y595190
X43190Y598410
X43210Y595180
X35085Y591621
X32609Y591538
X30212Y591417
X27495Y591409
X17156Y581481
X17139Y589683
X17108Y585513
X15770Y587700
X15800Y583500
X1600Y592500
X1539Y586183
X1439Y589783
Y582583
X-900Y592500
X-4500Y594000
X-12450Y590965
X43190Y601910
X63500Y602000
X66500
X69500
Y615500
X72500Y602000
Y615500
X75500Y602000
Y615500
X78500Y602000
Y612000
Y615500
X81500Y602000
Y612000
Y615500
X82459Y618932
X91150Y618250
X93800Y618111
X101898Y611483
X102236Y614167
X105000Y614533
X106192Y604600
X114792
X119892Y612583
X120092Y604900
X123620Y604499
Y612599
X126580Y606549
Y610300
X130313Y604499
Y612649
X132959Y606700
Y610300
X136806Y604750
Y607350
X136780Y609999
Y612599
X141893Y604536
X141880Y607140
Y609749
X141906Y612350
X147045Y604499
Y612649
X150391Y606549
Y610700
X153738Y604499
Y612649
X157084Y606549
Y610700
X160431Y604499
Y612599
X163391Y606549
Y610300
X166974Y612649
X167124Y604499
X169770Y606700
Y610300
X173617Y604750
Y607350
X173591Y609999
Y612599
X178704Y604536
X178691Y607140
Y609749
X178717Y612350
X183856Y604499
Y612649
X187202Y606549
Y610700
X190549Y604499
Y612649
X193895Y606549
Y610700
X197242Y604499
Y612599
X200202Y606549
Y610300
X203935Y604499
Y612649
X206581Y606700
Y610300
X210428Y604750
Y607350
X210402Y609999
Y612599
X215515Y604536
X215502Y607140
Y609749
X215528Y612350
X220667Y604499
Y612649
X224013Y606549
Y610700
X227360Y604499
Y612649
X230706Y606549
Y610700
X234053Y604499
Y612599
X237013Y606549
Y610300
X240746Y604499
Y612649
X243392Y606700
Y610300
X247239Y604750
Y607350
X247213Y609999
Y612599
X252326Y604536
X252313Y607140
Y609749
X252339Y612350
X257478Y604499
Y612649
X260824Y606549
Y610700
X264171Y604499
Y612449
X267517Y606549
Y610700
X270864Y604499
Y612399
X273824Y606549
Y610300
X277407Y612449
X277557Y604499
X280203Y606700
Y610300
X284050Y604750
Y607350
X284024Y609999
Y612599
X289137Y604536
X289124Y607140
Y609749
X289150Y612350
X294289Y604499
Y612249
X297635Y606549
Y610700
X300982Y604499
Y612249
X304328Y606549
Y610700
X307675Y611600
X308157Y607220
X311021Y604614
Y609864
X314368Y607292
Y612457
X317714Y604614
Y609864
X321061Y607292
Y612457
X324407Y604499
Y609864
X327754Y607292
Y612457
X331100Y604614
Y609864
X334447Y607292
Y612457
X337793Y604499
Y609864
X341140Y607292
Y612457
X344486Y604614
Y609864
X347833Y607292
Y612357
X351179Y604499
X352109Y609918
X354526Y607292
X354525Y612358
X357872Y604614
Y612242
X361218Y604614
Y612242
X364565Y604614
Y612242
X367170Y611759
X367911Y604614
X371134Y612453
X371312Y604709
X374039Y611186
X378600Y606200
X394682Y607292
Y612657
X398029Y604499
Y609864
X401375Y607292
X401376Y612658
X404722Y604499
Y609864
X408068Y607292
Y612657
X411415Y604614
Y609864
X414761Y607292
Y612657
X418108Y604499
Y609864
X421454Y607292
Y612560
X424801Y604614
Y609864
X428147Y607292
Y612657
X431494Y604499
Y609864
X434840Y607292
Y612657
X438187Y604614
Y609864
X441533Y607292
Y612557
X444880Y604614
Y609864
X447744Y607220
X447766Y612659
X451573Y604499
Y612599
X454533Y606549
Y610300
X458266Y604499
Y612649
X460912Y606700
Y610300
X464732Y609999
Y612599
X464758Y604750
Y607350
X469845Y604536
X469833Y607140
X469832Y609749
X469858Y612350
X474998Y604499
Y612649
X478344Y606549
Y610700
X480950Y612430
X481691Y604499
X485037Y607230
Y610700
X488384Y604499
Y612599
X491344Y606549
X491724Y611668
X495077Y604499
Y612649
X497723Y606700
X498092Y611200
X501544Y609999
Y612599
X501570Y604750
Y607350
X506644Y607140
Y609749
X506657Y604536
X506670Y612350
X511809Y604499
Y612649
X515155Y606549
Y610700
X518502Y604499
Y612649
X521848Y606549
Y610700
X525195Y604499
Y612599
X528155Y606549
Y610300
X531888Y604499
Y612649
X534534Y606700
Y610300
X538381Y604750
Y607350
X538355Y609999
Y612599
X543468Y604536
X543455Y607140
Y609749
X543481Y612350
X548620Y604499
Y612649
X551966Y606549
Y610700
X555313Y604499
Y612649
X558659Y606549
Y610700
X562006Y604499
Y612599
X564966Y606549
Y610300
X568699Y604499
Y612649
X571345Y606700
Y610300
X575192Y604750
Y607350
X575166Y609999
Y612599
X580279Y604536
X580266Y607140
Y609749
X580292Y612350
X585431Y604499
Y612649
X588777Y606549
Y610700
X592124Y604499
Y612649
X595470Y606549
Y610700
X598817Y604499
Y612649
X602163Y604499
Y612657
X605510Y604499
Y612657
X608856Y604499
Y612657
X612203Y604499
Y612657
X615549Y604499
Y612657
X620033Y608878
X627705Y611973
X629977Y613024
X631741Y615759
X655100Y611500
Y614100
X711500Y616274
X712106Y604050
Y606650
X713132Y609306
X713500Y618000
X716106Y609050
X721106Y609550
X724106
X726857Y610871
X727000Y606600
X729616Y610863
X732500Y611000
X733032Y604000
X755000Y614500
X755800Y604600
X764400
X769500Y612583
X769700Y604900
X773228Y604499
Y612599
X776188Y606549
Y610300
X779921Y604499
Y612649
X782567Y606700
Y610300
X786414Y604750
Y607350
X786388Y609999
Y612599
X791501Y604536
X791488Y607140
Y609749
X791514Y612350
X796653Y604499
Y612649
X799999Y606549
Y610700
X803346Y604499
Y612649
X806692Y606549
Y610700
X810039Y604499
Y612599
X812999Y606549
Y610300
X816582Y612649
X816732Y604499
X819378Y606700
Y610300
X823225Y604750
Y607350
X823199Y609999
Y612599
X828312Y604536
X828299Y607140
Y609749
X828325Y612350
X833464Y604499
Y612649
X836810Y606549
Y610700
X840157Y604499
Y612649
X843503Y606549
Y610700
X846850Y604499
Y612599
X849810Y606549
Y610300
X853543Y604499
Y612649
X856189Y606700
Y610300
X860036Y604750
Y607350
X860010Y609999
Y612599
X865123Y604536
X865110Y607140
Y609749
X865136Y612350
X870275Y604499
Y612649
X873621Y606549
Y610700
X876968Y604499
Y612649
X880314Y606549
Y610700
X883661Y604499
Y612599
X886621Y606549
Y610300
X890354Y604499
Y612649
X893000Y606700
Y610300
X896847Y604750
Y607350
X896821Y609999
Y612599
X901934Y604536
X901921Y607140
Y609749
X901947Y612350
X907086Y604499
Y612649
X910432Y606549
Y610700
X913779Y604499
Y612449
X917125Y606549
Y610700
X920472Y604499
Y612399
X923432Y606549
Y610300
X927015Y612449
X927165Y604499
X929811Y606700
Y610300
X933632Y609999
Y612599
X933658Y604750
Y607350
X938745Y604536
X938732Y607140
Y609749
X938758Y612350
X943897Y604499
Y612249
X947243Y606549
Y610700
X950590Y604499
Y612249
X953936Y606549
Y610700
X957283Y611600
X957765Y607220
X960629Y604614
Y609864
X963976Y607292
Y612457
X967322Y604614
Y609864
X970669Y607292
Y612457
X974015Y604499
Y609864
X977362Y607292
Y612457
X980708Y604614
Y609864
X984055Y607292
Y612457
X987401Y604499
Y609864
X990748Y607292
Y612457
X994094Y604614
Y609864
X997441Y607292
Y612357
X1000787Y604499
Y609864
X1004134Y607292
X1004133Y612358
X1007480Y604614
Y612242
X1010826Y604614
Y612242
X1014173Y604614
Y612242
X1016778Y611759
X1017519Y604614
X1020700Y604600
X1020800Y612600
X1023200Y610700
X1029777Y613581
X1044290Y607292
X1044291Y612658
X1047637Y604499
Y609864
X1050983Y607292
X1050984Y612658
X1054330Y604499
Y609864
X1057676Y607292
Y612657
X1061023Y604614
Y609864
X1064369Y607292
Y612657
X1067716Y604499
Y609864
X1071062Y607292
Y612560
X1074409Y604614
Y609864
X1077755Y607292
Y612657
X1081102Y604499
Y609864
X1084448Y607292
Y612657
X1087795Y604614
Y609864
X1091141Y607292
Y612557
X1094488Y604614
Y609864
X1097352Y607220
X1097374Y612659
X1101181Y604499
Y612599
X1104141Y606549
Y610300
X1107874Y604499
Y612649
X1110520Y606700
Y610300
X1114340Y609999
Y612599
X1114366Y604750
Y607350
X1119440Y607140
Y609749
X1119453Y604536
X1119466Y612350
X1124606Y604499
Y612649
X1127952Y606549
Y610700
X1131299Y604499
Y612649
X1134645Y606549
Y610700
X1137992Y604499
Y612599
X1140952Y606549
X1141332Y611668
X1144685Y604499
Y612649
X1147331Y606700
X1147700Y611200
X1151178Y604750
Y607350
X1151152Y609999
Y612599
X1156265Y604536
X1156252Y607140
Y609749
X1156278Y612350
X1161417Y604499
Y612649
X1164763Y606549
Y610700
X1168110Y604499
Y612649
X1171456Y606549
Y610700
X1174803Y604499
Y612599
X1177763Y606549
Y610300
X1181496Y604499
Y612649
X1184142Y606700
Y610300
X1187989Y604750
Y607350
X1187963Y609999
Y612599
X1193076Y604536
X1193063Y607140
Y609749
X1193089Y612350
X1198228Y604499
Y612649
X1201574Y606549
Y610700
X1204921Y604499
Y612649
X1208267Y606549
Y610700
X1211614Y604499
Y612599
X1214574Y606549
Y610300
X1218307Y604499
Y612649
X1220953Y606700
Y610300
X1224800Y604750
Y607350
X1224774Y609999
Y612599
X1229887Y604536
X1229874Y607140
Y609749
X1229900Y612350
X1235039Y604499
Y612649
X1238385Y606549
Y610700
X1241732Y604499
Y612649
X1245078Y606549
Y610700
X1248425Y604499
Y612649
X1251771Y604499
Y612657
X1255120Y612634
X1258464Y604499
Y612657
X1261811Y604499
Y612657
X1263800Y606800
X1265157Y604476
Y612657
X1296295Y615596
X1301384Y618119
X1306556Y607558
X1306600Y610000
X1309100Y601000
X1311876Y619501
X1312100Y601000
X1314476Y619501
X1315100Y601000
X1318100
X1321100
X1324200Y600100
Y602700
Y605100
Y607500
Y610100
X1360100
X1360200Y602000
Y606300
X1360261Y612573
X1361500Y604200
X1361900Y608200
X1363761Y610073
Y612573
X1371100Y615756
X1373838Y616161
X1375900Y604156
Y606656
X1375961Y600673
Y609173
X1376556Y615756
X1380890Y615820
X1382200Y606300
X1382586Y609602
X1382605Y612102
X1384744Y605689
X1385000Y602700
X1387050Y615350
X1445145Y605727
X1448071Y605981
X1450720Y606067
X1453451Y606114
X1453628Y603368
X1456100Y606200
X1456277Y603454
X1460200Y606200
X1463419Y606912
X1465334Y618564
X1467839Y618964
X1469200Y610739
X1469301Y607790
X1470356Y618000
X1472932Y619131
X1475812Y611732
X1475883Y619217
X1478329Y611671
X1478500Y619300
X1480760Y611602
X1483279Y619100
X1484312Y611732
X1487912Y611632
X1491512Y611732
X1492750Y615903
X1494100Y613280
X1497097Y613043
X1497800Y610000
X1504700Y608500
Y611100
X1508550Y619810
X1510450Y600800
X1511350Y613000
X1513700Y619900
X1513867Y612939
X1516367
X1516400Y619800
X1518900
X1519850Y613000
X1523450Y612900
X1527050Y613000
X1529067Y615784
X1529697Y613384
X1532160Y613408
X1532270Y610764
X1534928Y610532
X1534948Y613302
X1537711Y613397
X1538337Y601097
X1538679Y615641
X1540700Y613700
X1541162Y607903
X1541384Y601262
X1543697Y606719
X1544050Y615296
X1545407Y604713
X1546075Y618145
X1552400Y607600
X1554900Y607100
X1556200Y602400
X1560400Y611600
X1561700Y602200
X1564300Y611500
X1564400Y605500
X1570660Y601563
X1573260Y601600
X1573500Y619500
X1577000
X1579680Y610279
X1579900Y606050
X1587504Y605496
Y607996
X1590004Y605496
Y607996
X1590530Y610620
X1590881Y618788
X1593519Y618736
X1594110Y611510
X1600950Y618250
X1601489Y602812
X1602150Y610720
X1603550Y618250
X1603869Y604450
Y608450
X1613349Y603250
X1615862Y605507
X1617600Y619800
X1619700Y617300
X1640921Y605334
X1644856Y604930
X1650869Y609200
Y614200
X1652700Y600850
X1653970Y607340
X1654100Y615790
X1658369Y602250
Y606250
X1661200Y601300
Y607300
X1699106Y618018
X1701291Y602268
X1710000Y600000
Y604500
X1716950Y603450
X1724092Y618700
X1725133Y614896
X1728341Y614851
X1739714Y604967
X1746052Y614796
X1750399Y603201
X1750739Y618718
X1757319Y606953
X1758550Y604350
X1764823Y613600
X1764912Y618718
X1770600Y600800
X1772158Y610960
X1778400Y618900
X1782700Y610900
X1787500Y600500
X1788290Y612006
X1791500Y606500
X1794500Y612500
X1805000Y606500
X1805500Y603100
X1811500Y603500
X1906200Y607800
X1916050Y604450
X1919900Y604550
X1922900Y604450
X1924000Y611391
X1927000Y614500
X1930500Y616100
Y618900
X1934350Y609250
X1936770Y607210
X1938130Y601480
X1959400Y601100
X1961700Y616700
Y619500
X1963300Y612800
X1965400Y619500
X1776500Y621200
X1735000Y621002
X1586700Y620100
X1569495Y623365
X1566520Y623382
X1563827Y621376
X1560747Y623576
X1557575Y623559
X1554800Y620910
X1552198Y623479
X1540477Y620308
X1511204Y620056
X1505679Y620111
X1503008Y620018
X1500445Y619956
X1480975Y620100
X1461000Y623400
X1458000
X1455000
X1451314Y623298
X1448200Y623400
X1445200
X1442200
X1390851Y620689
X1386921
X1307600Y620100
X1046500Y623500
X728000
X456910Y623320
X453250
X427324Y623541
X413324Y623559
X399824
X386970Y623539
X91952Y620900
X89360Y620310
X86230Y620250
T04
X267859Y209109
X264092Y242260
X267859Y248109
X264179Y261760
Y331960
X267859Y345609
X264179Y347560
X267859Y392410
X274619Y400209
X277999Y398260
X271239
X274619Y396309
X271239Y394359
X277999Y374860
Y355360
X271239Y347560
Y339760
X277999Y335860
X271239Y331960
X277999Y324160
Y273460
X274619Y271509
X277999Y265660
X271239Y261760
X277999Y257860
X271239Y253960
Y242260
X277999Y226660
Y218860
X274619Y209109
X271239Y207159
X274619Y205210
X271239Y203260
X274619Y201309
X277999Y199360
X288139Y201309
X281379Y209109
X288139
Y220809
Y228610
X281379Y236409
X288139Y240309
X281379Y244209
X284759Y250060
X288139Y259809
Y267609
X284759Y320260
X281379Y322209
X288139
X281379Y330009
X288139
X284759Y335860
X281379Y341709
X284759Y347560
Y355360
X281379Y361209
Y369010
X288139
X284759Y374860
X281379Y380709
Y388509
X288139
X284759Y394359
X281379Y400209
X294899
X291519Y394359
X294899Y388509
Y380709
X298279Y374860
Y367060
X294899Y361209
X298279Y355360
Y347560
X294899Y341709
X298279Y335860
X294899Y330009
Y326109
X298279Y324160
X291519
X298279Y320260
X291519
X298279Y273460
X291519
X294899Y271509
X298279Y269560
X294899Y267609
Y259809
Y252009
Y240309
Y232509
X298279Y222760
X294899Y216909
Y205210
Y197409
X301659Y216909
X308418
X305039Y222760
X301659Y232509
X305039Y238360
X301659Y244209
X308418Y248109
X301659Y252009
X305039Y257860
X301659Y263709
Y271509
X308418
X305039Y335860
X301659Y341709
X308418Y349509
X305039Y355360
X301659Y361209
X305039Y374860
X301659Y380709
X308418
X315178Y384609
Y380709
X318558Y374860
X315178Y369010
X318558Y363160
X311798
X318558Y331960
X311798
X315178Y326110
Y271509
X318558Y265660
X311798
X315178Y248109
X311798Y246160
X315178Y244209
X311798Y242260
Y234460
X318558Y230559
X311798Y226660
X318558Y222760
X328698Y224709
Y228610
Y236409
X321938Y240309
X328698Y244209
X321938Y252009
X328698Y255909
X325318Y261760
X321938Y271509
X328698
Y275409
X325318Y277360
X321938Y279310
X328698
X321938Y326110
X325318Y331960
X321938Y341709
X328698
X321938Y345609
X325318Y351460
X321938Y357309
X328698Y361209
X321938Y369010
X328698
Y372909
X335458Y376809
X338838Y374860
X332078
Y370959
X335458Y369010
X332078Y367060
X335458Y365109
X338838Y363160
X335458Y357309
X332078Y351460
X335458Y341709
X338838Y335860
X332078
X335458Y322209
Y279310
X338838Y277360
X332078
X335458Y275409
X338838Y273460
X332078
X335458Y271509
X338838Y269560
Y261760
X332078
X335458Y255909
X338838Y250060
X335458Y240309
Y232510
X338838Y230560
X332078
X335458Y228610
X332078Y226660
Y222760
X335458Y220809
X338838Y214960
Y207158
Y203258
X342218Y205210
X345598Y211060
X348978Y213009
X342218Y216909
X345598Y218860
Y222760
X342218Y224709
X348978
X345598Y230559
Y234460
X342218Y236409
X348978
X345598Y242260
X342218Y248109
X345598Y250060
X342218Y252009
X348978
X345598Y253960
X348978Y255909
X345598Y257860
X348978Y259809
X345598Y261760
X342218Y341709
X345598Y347560
X342218Y349509
X345598Y351460
X342218Y357309
X348978
X345598Y363160
X342218Y369010
X348978
X345598Y374860
X342218Y380709
X348978
Y384609
X345598Y386560
X341892Y396301
X351192Y402800
X359117Y386560
X355737Y380709
X359117Y374860
X352357
X355737Y369010
X359117Y363160
X352357
X355737Y357309
X359117Y351460
X352357
X359117Y347560
X352357
X355737Y345609
X359117Y343660
X352357
X355737Y341709
X352357Y339760
Y257860
X355737Y255909
X359117Y253960
X352357
X355737Y252009
X359117Y250060
X352357
X359117Y242260
X352357
X355737Y236409
X359117Y230559
X352357
X355737Y224709
X359117Y218860
X352357
X359117Y211060
X357987Y193507
X365877Y218860
X362497Y224709
X369257
X365877Y230559
X362497Y236409
X369257
X365877Y242260
Y246160
X362497Y248109
X369257
X365877Y250060
X362497Y252009
Y345609
Y349509
X365877Y351460
X362497Y357309
X369257
Y361209
X365877Y363160
X362497Y369010
X369257
X365877Y374860
X362497Y380709
X369257
X379397Y386560
X372637
X376017Y380709
X379397Y374860
X372637
X376017Y369010
X379397Y363160
X372637
X376017Y357309
X379397Y355360
Y351460
X372637
X376017Y349509
X379397Y246160
X372637
X376017Y244209
X379397Y242260
X372637
X379397Y234460
X372637Y230559
X376017Y224709
X379397Y218860
X372637
Y211060
X379397Y207159
X378267Y193507
X386157Y211060
Y218860
X382777Y224709
X389537
X386157Y230559
X389537Y236409
X382777Y240309
X389537
X386157Y242260
X382777Y244209
X389537
X386157Y246160
X382777Y353409
Y357309
X389537
X386157Y363160
X382777Y369010
X389537
X386157Y374860
X382777Y380709
X389537
X386157Y386560
X398546Y402900
X399676Y386560
X392916
X396296Y380709
X399676Y374860
X392916
X396296Y369010
X399676Y363160
X392916
X396296Y357309
X399676Y355360
X392916Y246160
X396296Y244209
X399676Y242260
X392916
X396296Y240309
Y236409
X399676Y230559
X392916
X396296Y224709
X399676Y218860
X392916
X399676Y211060
X392916
X407706Y216909
Y224709
Y236409
Y244209
X403056Y369010
Y380709
Y396309
X402892Y400400
X411086Y394359
Y386560
Y382660
Y378760
X415634Y243496
Y231797
X419214Y225947
Y218147
X425974Y222047
X429354Y231797
X422594Y235696
X429354Y239596
X422594Y247396
X423714Y358547
Y366347
Y378047
X427094Y387796
X423714Y393647
X433854Y387796
X430474Y381947
X437233Y378047
X430474Y370247
X437233Y366347
X430474Y362447
Y358547
X433854Y356596
X439764Y263699
X436113Y235696
X439493Y229847
X436113Y227896
X439493Y225947
X432733
X439493Y222047
X432733
X436113Y220096
X442873
X446253Y222047
Y225947
X442873Y227896
X449633Y231797
X442873Y235696
X449633Y239596
X444752Y264188
X449288Y266435
X447800Y335900
X443993Y354647
X440613Y360496
X447373
X443993Y370247
Y374147
X440613Y376096
Y383896
X447373
X443993Y389747
X450753
X454133Y383896
X457513Y374146
X450753
X454133Y368296
Y360496
X450753Y354647
X457513Y350747
X452865Y270081
X459773Y253247
X453013
X456393Y247396
Y235696
X459773Y229847
X453013Y225947
X459773Y222047
X456393Y220096
X463153
X466533Y225947
X463153Y227896
Y235696
X469913
X466533Y241547
X463153Y247396
X466533Y253247
X469913Y266896
X466734Y287074
X466066Y292452
X466100Y300021
X464273Y342947
X460893Y344896
X464273Y354647
X460893Y360496
X467653
X460893Y368296
X464273Y374146
X467653Y379996
X460893Y383896
X467653Y387796
X474413Y383896
X477792Y374146
X471033
X474413Y368296
Y360496
X471033Y354647
X474413Y344896
X471033Y339047
X476672Y262996
X473292Y253247
X476672Y247396
X473292Y241547
X476672Y235696
X473292Y225947
Y222047
X476672Y220096
X480052Y210346
X483432Y212296
Y216196
Y220096
X480052Y222047
Y225947
X483432Y231797
Y239596
Y247396
X480052Y253247
X486812
Y261047
X483432Y262996
X484552Y276646
X481172Y286396
X487932Y294196
Y298096
Y301996
X484552Y303947
X487932Y305896
X484552Y311747
X487932Y313696
X481172Y317596
X484552Y319546
X481172Y321496
Y325396
X484552Y331247
X481172Y333196
X484552Y342947
X487932Y356596
X481172Y364396
X484552Y374146
X481172Y383896
X487932
X484552Y389747
X494692Y399496
X491312Y393647
X494692Y387796
Y383896
X498072Y381947
X494692Y379996
X498072Y378047
Y374146
Y370247
X491312Y354647
Y342947
Y315647
X498072Y307847
X491312Y303947
X494692Y301996
Y298096
X491312Y296147
X498072Y292247
X494692Y290296
X498072Y288347
X491312
X498072Y284447
X491312
X494692Y282496
X498072Y280547
X491312
X498072Y276647
X491312
X498072Y272747
X491312
X494692Y266896
X498072Y261047
X494692Y259096
X498072Y257147
Y253247
X494692Y239596
Y231797
Y220096
X498072Y214247
X494692Y212296
X504832Y214247
X501452Y216196
X508212
X504832Y218147
Y222047
X501452Y227896
X508212
X504832Y237647
X501452Y243496
X508212
X504832Y249347
X501452Y251296
X508212
X501452Y255196
X504832Y257147
X501452Y262996
Y270796
X504832Y272747
Y276647
Y280547
X508212Y282496
X504832Y284447
X501452Y286396
X508212
X504832Y288347
Y292247
X501452Y305896
X504832Y307847
X501452Y309797
Y337096
X508212Y364396
Y368296
X504832Y370247
X501452Y372197
X508212
X504832Y374146
X501452Y376096
X508212
Y383896
X504832Y385847
Y393647
Y401446
X518352Y405347
Y401447
X511592
X514972Y395597
X518352Y393647
X514972Y391696
X511592Y389747
X514972Y387796
Y376096
Y368296
X511592Y366347
X514972Y364396
X511592Y362447
X514972Y360496
X511592Y358547
X518352Y354647
X511592
X518352Y350747
Y346847
Y335147
Y311747
X511592
Y303947
Y292245
X518352Y284447
X514972Y282496
X518352Y280547
X511592
X518352Y276646
X511592Y276647
Y272747
X518352Y268847
X511592Y237647
X514972Y231797
X518352Y225947
X514972Y216196
X518352Y214247
X511592
X514972Y212296
X518352Y210345
X514972Y208397
X525111Y202547
Y210346
X521731Y212296
X528491
X525111Y225947
Y233746
X528491Y239596
X525111Y241547
Y249347
X528491Y251296
Y259096
X521731Y262996
X525111Y264947
X528491Y266896
X521731Y270796
Y278596
Y282496
X528491
Y305896
X525111Y315647
Y319547
X528491Y321496
X525111Y323446
X528491Y325396
X525111Y327347
X521731Y329296
X528491
X525111Y331247
X521731Y333196
X528491
X521731Y337096
Y340996
X528491
Y344896
X525111Y346847
X528491Y348796
X521731Y352696
X528491
Y376096
Y379996
X521731Y383896
X528491
X525111Y385847
X521731Y387796
X528491
X525111Y389747
X521731Y391696
Y395597
X531871Y381947
X535251Y379996
X531871Y378047
X535251Y376096
X538631Y374146
X535251Y372197
Y368296
X531871Y366347
X535251Y364396
X538631Y362447
X531871
X535251Y360496
X538631Y358547
X531871
X538631Y354647
Y350747
X535251Y348796
X538631Y346847
X535251Y344896
X538631Y342947
X531871
X535251Y340996
X531871Y339047
X535251Y337096
X538631Y331247
X531871
X538631Y327347
Y323446
X531871
X535251Y317596
X538631Y315647
X531871
X535251Y313696
X538631Y307847
X535251Y305896
X538631Y303947
Y300047
X535251Y298096
X538631Y296147
X531871
X535251Y286396
Y282496
X531871Y280547
X538631Y276646
X535251Y274696
X538631Y272747
X531871
X538631Y268847
Y264947
X535251Y262996
X538631Y253247
X531871
X538631Y245447
X531871
X538631Y241547
Y233746
X531871
Y225947
X535251Y220096
X531871Y214247
X535251Y212296
X531871Y202547
X542011Y212296
X545391Y214247
X548771Y216196
X545391Y218147
X542011Y220096
X548771
Y223996
X542011Y231797
X548771
X542011Y243496
X545391Y245447
Y249347
X542011Y251296
X545391Y257147
X542011Y259096
X548771
X542011Y262996
X548771Y274696
X542011Y278596
Y282496
Y290296
X548771Y298096
X542011Y301996
X548771
X542011Y305896
X548771
X542011Y309797
X545391Y311747
X542011Y313696
Y317596
X548771
Y321496
X545391Y323446
X542011Y325396
X545391Y327347
X542011Y329296
Y333196
X548771
X542011Y337096
X545391Y339047
X542011Y340996
Y344896
X548771
Y348796
X545391Y350747
X542011Y356596
X548771Y364396
X542011Y387796
X548771
X545391Y389747
X542011Y391696
X545391Y393647
X542011Y395597
X548990Y403670
X555750Y399770
X552151Y393647
X559212Y389747
X552151Y385847
Y381947
X555531Y379996
Y372197
X552151Y370247
X559211Y366347
X552151
Y362447
X558911Y354647
X552151
X555531Y352696
X558911Y350747
X555531Y348796
X552151Y346847
X555531Y344896
X552151Y342947
X555531Y340996
X558911Y339047
X552151
X555531Y337096
X552151Y335147
Y331247
X559211Y331103
X555531Y329296
X559211Y327347
X552151
X555531Y325396
X559211Y323446
X555531Y321496
X552151Y319547
X555831Y317446
X552151Y315647
X555831Y313696
X552151Y311747
Y307847
Y303947
X555831Y301996
X552151Y300047
Y292245
X559211Y284447
X552151Y280547
X555531Y270796
X552151Y264947
X555531Y259096
X552151Y253247
X555531Y243496
X552151Y237647
X555531Y227896
X552151Y222047
X555531Y220096
X562861Y205503
X566051Y211555
X562616Y223996
X562640Y231735
X560884Y290296
X562591Y337096
Y340996
X563500Y360500
X660600Y170000
X670600Y144900
Y150000
X680200Y432100
X746130Y430130
X917467Y392410
X913787Y351460
X917467Y345609
X913787Y335860
X917467Y271509
X913787Y257860
X917467Y248109
X913700Y242260
X927607Y199360
X924227Y201309
Y205210
Y209109
X927607Y222760
Y226660
Y238360
X920847Y242260
X927607Y246160
X920847Y250060
Y253960
Y261760
X927607
X924227Y271509
X927607Y273460
Y324160
X920847Y331960
X927607Y335860
X920847Y339760
Y351460
X927607
Y359260
Y370959
Y378760
X924227Y396309
X930987Y400209
X937747Y396309
X930987Y392410
X934367Y386560
Y378760
X937747Y372909
X934367Y367060
Y355360
Y347560
X930987Y341709
X934367Y335860
X937747Y330009
X930987
X937747Y322209
X930987
X934367Y320260
Y269560
X937747Y267609
X930987Y263709
X934367Y261760
X937747Y259809
X930987Y255909
X934367Y250060
X930987Y248109
X937747Y244209
X934367Y242260
Y238360
X937747Y228610
X930987
X934367Y222760
X930987Y216909
X934367Y211060
X937747Y209109
X930987
X934367Y203260
X937747Y201309
X944507Y197409
Y205210
Y209109
Y216909
X947887Y222760
X944507Y232509
Y240309
X947887Y250060
X944507Y252009
X947887Y257860
X944507Y259809
Y267609
X947887Y269560
X944507Y271509
X941127Y273460
X947887
X941127Y320260
X947887
X941127Y324160
X947887
X944507Y326110
Y330009
X947887Y335860
X944507Y341709
X947887Y347560
X944507Y357309
Y365109
Y376809
X947887Y382660
X941127Y386560
X944507Y392410
Y400209
X954647Y382660
X958026Y376809
X951267Y372909
Y365109
X954647Y359260
X951267Y353409
X958026Y349509
X951267Y341709
X954647Y335860
X958026Y271509
X951267
Y263709
X954647Y261760
Y257860
Y253960
X951267Y252009
X958026Y248109
X951267Y244209
X954647Y238360
Y234460
X951267Y232509
X954647Y222760
X951267Y220809
X958026Y216909
X951267
Y213009
X968166Y222760
X961406Y226660
X964786Y228610
X968166Y230559
X961406Y234460
X968166
X964786Y236409
X961406Y242260
X964786Y244209
X961406Y246160
X964786Y248109
X968166Y250060
X964786Y263709
X961406Y265660
X968166
Y273460
X964786Y275409
Y326110
X961406Y331960
X968166
X964786Y361209
X961406Y367060
X964786Y372909
Y380709
Y384609
X978306Y372909
X971546
X978306Y369010
X971546Y365109
X978306Y361209
X971546Y357309
X974926Y351460
X971546Y345609
Y341709
X978306Y337809
X974926Y331960
X971546Y326110
X978306Y279310
X971546
X974926Y277360
X978306Y275409
Y271509
X971546
X978306Y263709
X974926Y261760
Y257860
X971546Y252009
X974926Y246160
X978306Y244209
X971546
X978306Y240309
X971546
X978306Y236409
Y228610
X971546
X978306Y224709
X988446Y203258
Y207158
Y214960
X985066Y220809
X981686Y222760
X988446
X981686Y226660
X985066Y228610
X981686Y230559
X985066Y232509
Y240309
X981686Y246160
Y253960
Y257860
X988446
X985066Y263709
X981686Y265660
X988446Y269560
X985066Y271509
X981686Y273460
X988446
X985066Y275409
X981686Y277360
X988446
X985066Y279310
Y333909
X981686Y343660
X988446
X981686Y351460
X985066Y357309
X988446Y363160
X985066Y365109
X981686Y367060
X985066Y369010
X981686Y370959
X988446
X981686Y374860
X985066Y376809
X988446Y378760
X991500Y396301
X998586Y384609
X991826
X995206Y378760
Y374860
X998586Y372909
X995206Y367060
Y363160
X998586Y361209
X991826
X995206Y355360
X991826Y349509
X995206Y347560
X998586Y345609
Y341709
Y337809
X991826
X995206Y261760
X998586Y259809
X995206Y257860
X998586Y255909
X995206Y253960
X998586Y252009
X995206Y250060
Y242260
X991826Y240309
X998586Y236409
X991826
X995206Y234460
X998586Y228610
X991826
X998586Y224709
X991826
X995206Y222760
Y218860
X991826Y216909
X998586Y213009
X991826
X995206Y211060
X991826Y209109
X995206Y207159
X1005345Y213009
Y216909
X1001965Y218860
X1008725
X1005345Y224709
X1001965Y230559
X1008725
Y234460
X1005345Y236409
X1001965Y242260
X1008725
X1001965Y246160
X1008725
X1001965Y250060
X1008725
X1005345Y252009
X1001965Y253960
X1008725
X1005345Y255909
X1001965Y257860
Y339760
X1005345Y341709
X1001965Y343660
Y347560
X1008725
X1001965Y355360
X1008725
X1005345Y361209
X1001965Y367060
X1008725
X1005345Y372909
X1001965Y378760
X1008725
X1005345Y384609
X1000800Y402800
X1018865Y384609
X1012105
X1015485Y378760
X1018865Y372909
X1012105
X1018865Y369010
X1015485Y367060
X1018865Y361209
X1012105
X1015485Y355360
Y351460
X1012105Y349509
X1015485Y347560
X1012105Y345609
Y252009
X1015485Y250060
X1018865Y248109
X1012105
X1015485Y246160
Y242260
X1018865Y236409
X1012105
X1015485Y230559
X1018865Y228610
Y224709
X1012105
X1015485Y218860
X1018865Y213009
X1012105
X1022245Y207159
X1029005
X1025625Y213009
Y216909
X1022245Y218860
X1029005
X1022245Y222760
X1029005
X1025625Y224709
X1022245Y230559
X1029005
X1022245Y234460
X1025625Y236409
X1022245Y242260
X1029005
X1025625Y244209
X1022245Y246160
X1029005
X1025625Y349509
X1022245Y351460
X1029005
Y355360
X1025625Y361209
X1022245Y367060
X1029005
X1025625Y372909
X1022245Y378760
X1029005
X1025625Y384609
X1022245Y390460
X1039145Y384609
X1032385
X1035765Y378760
X1039145Y372909
X1032385
Y369010
X1035765Y367060
X1039145Y361209
X1032385
Y357309
X1035765Y246160
X1039145Y244209
X1032385
X1035765Y242260
X1039145Y240309
X1032385
X1039145Y236409
X1032385
X1035765Y234460
Y230559
X1032385Y228610
X1039145Y224709
X1032385
X1035765Y222760
Y218860
X1039145Y213009
X1032385
X1049284Y207159
X1042524Y211060
X1049284
X1045904Y213009
Y216909
X1042524Y218860
X1049284
X1042524Y222760
X1045904Y224709
Y228610
X1042524Y230559
X1049284
X1042524Y234460
X1049284
X1045904Y236409
Y240309
X1042524Y242260
X1049284
X1045904Y244209
X1042524Y246160
X1049284Y355360
X1045904Y361209
X1042524Y367060
X1049284
X1045904Y372909
X1042524Y378760
X1049284
X1045904Y384609
X1049284Y386560
Y390460
X1048154Y402900
X1052500Y400400
X1052664Y396309
Y372909
Y361209
X1057314Y236409
Y228610
Y216909
X1065242Y216196
X1068822Y222047
Y225947
X1065242Y227896
Y231797
Y243496
X1061055Y363160
X1064371Y367060
X1060963Y370959
X1060694Y378760
Y382660
Y386560
Y394359
X1073322Y393647
X1076702Y383896
X1073322Y378047
Y370247
X1076702Y364396
X1073322Y358547
X1072202Y247396
X1078962Y243496
X1075582Y241547
X1078962Y235696
X1072202
X1078962Y231797
X1072202Y227896
X1075582Y222047
X1072202Y220096
X1089101Y218147
X1085721Y220096
X1082341Y225947
X1089101Y229847
X1085721Y235696
X1082341Y241547
X1083462Y356596
X1080082Y358547
X1083462Y364396
X1086841Y370247
X1080082Y374146
X1086841Y378047
X1083462Y383896
X1080082Y389747
X1096981Y391696
X1090221Y387796
X1093601Y381947
X1090221Y376096
X1093601Y374146
Y370247
X1096981Y364396
X1090221Y360496
X1096981Y356596
X1093601Y354647
X1099391Y337001
X1095700Y265900
X1099241Y243496
X1095861Y241547
X1092481Y239596
X1099241Y235696
X1092481
X1099241Y231797
X1092481Y227896
X1095861Y225947
X1092481Y220096
X1109381Y218147
X1106001Y220096
X1102621Y222047
Y225947
X1109381Y229847
X1106001Y235696
X1102621Y241547
Y249347
X1109381
X1102621Y253247
X1106001Y255196
X1109381Y257147
Y264947
X1107600Y271900
X1105800Y336830
X1107121Y350747
X1100361Y354647
X1103741Y360496
X1100361Y362447
X1107121Y366347
X1100361Y370247
X1103741Y376096
X1100361Y381947
X1103741Y387796
X1113881Y389747
X1117261Y387796
Y383896
X1110501
X1117261Y379996
X1110501Y376096
X1113881Y370247
X1117261Y364396
X1110501Y360496
X1117261Y356596
X1110501
X1113881Y354647
X1110501Y344896
X1113881Y342947
X1114839Y320075
X1116096Y295809
X1115230Y289252
X1114340Y280560
X1112761Y255196
X1116141Y249347
X1119521Y243496
X1116141Y241547
X1119521Y235696
X1112761
Y227896
X1116141Y225947
X1112761Y220096
X1116141Y206446
X1129660Y210346
Y218147
X1126280Y220096
X1122900Y222047
Y225947
X1129660Y229847
X1126280Y235696
X1122900Y241547
X1126280Y247396
X1129660Y249347
X1122900Y253247
X1129660Y257147
X1120641Y339047
X1124021Y344896
X1120641Y346847
X1127400Y350747
X1120641Y354647
X1124021Y360496
X1120641Y362447
X1124021Y368296
X1127400Y370247
X1120641Y374146
X1127400
X1124021Y383896
X1120641Y389747
X1137540Y387796
X1130780
X1137540Y383896
X1130780
X1137540Y379996
X1134160Y374146
X1130780Y364396
X1137540Y356596
X1130780Y333196
X1134160Y331247
X1130780Y325396
Y321496
X1134160Y319547
X1130780Y317596
X1137540Y313696
X1134160Y303947
X1137540Y301996
Y286396
X1134160Y272747
X1133040Y262996
X1136420Y261047
X1133040Y255196
X1136420Y253247
X1133040Y247396
Y239596
Y231797
Y220096
Y216196
Y212296
X1136420Y210346
X1144300Y212296
X1147680Y214247
X1144300Y216196
X1147680Y218147
X1144300Y220096
X1147680Y229847
Y241547
Y253247
Y257147
X1144300Y259096
X1147680Y261047
X1140920Y272747
X1147680
X1140920Y276647
X1147680
X1140920Y280547
X1144300Y282496
X1140920Y284447
X1147680
X1140920Y288347
X1147680
X1144300Y290296
X1147680Y292247
X1140920Y315647
Y342947
Y354647
X1147680Y370247
Y374146
Y378047
X1144300Y379996
X1147680Y381947
X1144300Y383896
Y387796
X1140920Y393647
X1144300Y399496
X1140920Y401447
X1156699
X1157820Y383896
Y376096
X1151060
X1154440Y374146
X1157820Y372196
X1151060
X1154440Y370246
X1157820Y368296
Y364396
X1151060Y337096
X1157820Y309797
X1154440Y292247
Y288347
X1157820Y286396
X1151060
X1154440Y284447
X1157820Y282496
X1154440Y280547
Y276647
X1157820Y274696
X1154440Y272747
X1151060Y270796
X1154440Y268847
X1151060Y262996
Y255196
Y251296
X1157820Y243496
X1154440Y237647
X1157820Y227896
X1154440Y218147
X1164580Y208397
X1161200Y214247
X1167960
X1164580Y231797
X1161200Y237647
X1164580Y243496
X1167960Y268847
X1164580Y274696
X1161200Y276646
Y280547
X1167960
X1164580Y282496
X1167960Y284447
X1161200Y288347
Y292247
X1167960Y335147
Y346847
Y350747
X1161200Y354647
X1167960
X1161200Y358547
X1164580Y360496
X1161200Y362447
X1164580Y364396
X1161200Y366347
X1164580Y368296
Y376096
X1161200Y389747
X1164580Y391696
Y395597
X1161201Y401447
X1171339Y395596
Y391696
X1174719Y389747
X1178099Y387796
X1171339Y383896
X1178099Y376096
Y368296
Y352696
X1171339
Y340996
Y337096
X1178099Y333196
X1171339
X1174719Y331247
X1178099Y329296
X1171339
X1174719Y327347
X1178099Y325396
X1174719Y323446
X1178099Y321496
X1174719Y319547
X1171339Y282496
Y278596
Y270796
X1178099Y266896
X1174719Y264947
X1178099Y262996
X1171339
X1178099Y251296
X1174719Y245447
Y241547
X1178099Y239596
Y231797
X1171339Y227896
X1178099Y223996
X1174719Y222047
Y214247
X1181479
X1184859Y220096
Y227896
X1181479Y245447
X1188239
X1181479Y253247
X1188239
Y268847
X1181479Y280547
Y296147
X1188239
X1184859Y298096
X1188239Y300047
X1184859Y305896
X1188239Y307847
X1181479Y315647
Y323446
X1188239Y327347
X1181479Y331247
X1188239
Y350747
Y354647
X1181479Y358547
X1188239
X1184859Y360496
X1181479Y362447
X1188239
X1184859Y364396
X1181479Y366347
X1184859Y368296
Y372197
X1188239Y374146
X1184859Y376096
X1181479Y378047
X1184859Y379996
X1197100Y408200
X1198379Y383896
X1191619Y379996
X1198379Y376096
X1191619Y356596
X1194999Y350747
X1198379Y348796
X1191619Y344896
Y340996
Y337096
Y325396
X1194999Y323446
X1198379Y321496
X1191619Y313696
X1194999Y311747
X1198379Y274696
X1194999Y261047
X1191619Y235696
X1194999Y229847
X1198379Y223996
X1191619
X1194999Y218147
X1191619Y212296
X1208519Y218147
X1205139Y223996
Y235696
Y243496
X1201759Y253247
X1208519
X1205139Y255196
Y262996
Y270796
Y278596
X1208819Y284447
X1201759Y292247
X1212199Y227896
X1210070Y195300
X1315180Y169950
X1315130Y164870
X1325100Y145000
X1350100Y170000
X1375100Y447500
X1372028Y458125
X1377028
X1380100Y165000
Y160000
X1390100Y432500
Y452500
X1395375Y453561
X1487525Y377514
X1489475Y380894
X1487525Y384274
X1483868Y390233
X1487525Y397794
X1489475Y401174
Y407934
Y414694
X1487525Y418074
X1489475Y421454
Y457066
X1487525Y460446
Y480726
X1491425Y487486
Y480726
X1495325Y473966
X1499225Y467206
Y460446
Y453686
Y446926
X1493375Y443546
X1499225Y440166
X1493375Y436786
Y428214
Y421454
X1495325Y418074
X1491425
X1493375Y414694
Y407934
X1499225Y404554
X1493375Y401174
X1499225Y397794
X1495325
X1493375Y380894
X1499225Y377514
X1498183Y365405
X1503878Y364717
X1507025Y377514
X1501175Y380894
X1507025Y384274
X1501175Y387654
X1505075
Y394414
X1501175Y401174
X1505075
X1507025Y404554
X1501175Y421454
X1505075Y463826
X1508975
X1507025Y467206
X1516775Y477346
X1512875
Y470586
X1514825Y467206
X1510925
X1512875Y463826
X1515500Y448250
X1510925Y397794
X1516775Y394414
X1510925Y391034
X1512875Y387654
X1518725Y384274
X1510925
X1512875Y380894
X1518725Y377514
X1510925
X1522625Y384274
X1524575Y387654
X1528475
X1522625Y391034
X1528475Y394414
X1522625Y397794
X1528475Y401174
X1522625Y404554
X1520675Y463826
X1528475
X1520675Y470586
Y477346
X1524575
X1522625Y480726
X1526525
X1520675Y484106
X1524575
X1530425Y487486
Y480726
X1536275Y477346
X1534325Y473966
X1530425Y467206
X1536275Y463826
Y401174
X1534325Y397794
Y384274
Y377514
X1530425
X1542300Y376717
X1540175Y380894
Y387654
Y394414
Y401174
X1542125Y460446
X1546025
X1549925Y467206
Y480726
X1547975Y484106
X1557725Y487486
X1559675Y484106
X1551875
X1559675Y477346
Y470586
X1551875
X1557725Y467206
X1559675Y463826
X1557725Y460446
X1553825
X1551875Y443546
X1557725Y440166
Y418074
X1555775Y407934
X1551875Y401174
Y394414
Y387654
X1559675Y380894
X1563575
X1565525Y384274
X1563575Y387654
X1565525Y397794
X1561625Y411314
X1567475Y414694
X1565525Y418074
X1569425
X1563575Y421454
X1565525Y424834
X1561625Y440166
X1567475Y443546
X1565525Y446926
X1563575Y450306
X1565525Y453686
Y460446
X1563575Y463826
X1567475
X1561625Y467206
X1565525
X1569425
X1563575Y470586
X1561625Y473966
X1565525
X1567475Y477346
X1561625Y480726
X1563575Y484106
X1561625Y487486
X1571545Y482842
X1571375Y477346
Y421454
Y414694
Y407934
X1613741Y112341
X1654685Y121790
X1657835Y131239
X1664135
T05
X-18079Y-58764
X-13679
X-9279
X-4879
X-479
X-9079Y-54264
X-4679
X-279
X-17936Y-53779
X-13636Y-53679
X-9079Y-50164
X-4679
X-279
X-17936Y-49379
X-13636Y-49279
X-17936Y-44979
X-13636Y-44879
X-17936Y-40579
X-13636Y-40479
X-18079Y-35764
X-13679
X-9279
X-4879
X-479
X-14186Y196989
X-11586
X-14186Y199989
X-11586
X-7900Y200191
X-5300
X-2700Y200202
X-14084Y232215
X-11484
X-2600Y232300
X-7846Y232351
X-5246
X-14129Y235221
X-11484Y235215
X-11652Y445530
X-14839Y445588
X-261Y445673
Y448273
X-11652Y448530
X-14753Y448601
X-261Y450873
Y453473
X-3301Y601615
X-9599Y610630
X-3301Y619643
X-17194Y638753
X-12794
X-17179Y643156
X-12779
X-17179Y647556
X-12779
X-17179Y651956
X-12779
X-17179Y656356
X-12779
X-8379
X-3979
X-17179Y660756
X-12779
X-8379
X-3979
X97221
X92821
X88421
X84021
X79621
X75221
X70821
X66421
X62021
X57621
X53221
X48821
X44421
X40021
X35621
X31221
X26821
X22421
X18021
X13621
X9221
X4821
X421
X35621Y656356
X31221
X26821
X22421
X18021
X13621
X9221
X4821
X421
X35621Y651956
X31221
X26821
X22421
X18021
X13621
X9221
X4821
X35621Y647556
X31221
X26821
X22421
X18021
X13621
X9221
X4821
X35621Y643156
X31221
X26821
X22421
X18021
X13621
X9221
X4821
X97206Y638753
X92806
X88406
X84006
X79606
X75206
X70806
X66406
X62006
X57606
X53206
X48806
X44406
X40006
X35606
X31206
X26806
X22406
X18006
X13801Y624130
X4549Y620682
X23360Y620172
X27301Y610630
X23352Y601079
X4548Y600577
X13801Y597130
X98240Y499410
X95640
X93040
X90440
X87840
X98240Y496810
X95640
X93040
X90440
X87840
X95777Y494213
X92990Y494210
X90390
X87790
X90390Y491610
X87790
X28988Y460876
X26318Y460866
X23718
X21118
X28868Y457576
X26198Y457566
X23598
X20998
X1108Y455879
X28868Y454576
X26198Y454566
X23598
X20998
X2339Y453473
Y450873
Y448273
X8343Y446875
X5743
X2339Y445673
X5743Y444275
X87013Y436371
X84913Y434471
X81500Y427400
X80100Y425000
X78000Y423100
X76052Y420935
X81500Y412100
X79700Y409700
X77400Y407800
X98149Y399769
X81900Y398300
X79140Y397355
X76540
X71500Y266000
X68800
X65500Y265500
X62800
X60000
X71500Y263300
X68800
X57600Y262800
X57500Y260200
X98600Y258900
X96000
X93400
X90800
X88200
X19800Y257900
X57444Y257456
X98600Y256300
X96000
X93400
X90800
X88200
X98600Y253400
X96000
X93400
X90800
X88200
X57457Y251237
X98600Y250400
X96000
X93400
X90800
X88200
X57457Y248537
X98600Y247400
X96000
X93400
X90800
X88200
X57875Y245900
X55275
X53004Y244632
X98600Y244400
X96000
X93400
X90800
X88200
X58200Y239400
X55600
X53000Y239300
X99000Y236450
X96400
X93800
X91200
X88600
X58200Y236400
X55600
X53000Y236300
X99000Y233450
X96400
X93800
X91200
X88600
X58200Y233400
X55600
X53000Y233300
X99000Y230450
X96400
X93800
X91200
X88600
X58200Y230400
X55600
X53000Y230300
X99000Y227450
X96400
X93800
X91200
X88600
X58200Y227400
X55600
X53000Y227300
X36300Y224000
X33300
X30300
X23500
X20500
X17500
X5173Y224042
X2574Y223963
X-26Y223982
X5277Y221110
X36300Y221000
X33300
X30300
X23500
X20500
X17500
X2678Y221018
X5500Y218500
X64778Y218062
X64700Y212800
X36200Y211600
X33200
X30200
X23700
X20700
X17700
X6074Y211293
X3474Y211263
X875Y211336
X64700Y210100
X36200Y208600
X33200
X30200
X23700
X20700
X17700
X875Y208352
X6074Y208321
X3474Y208263
X58000Y206500
X50500Y205696
X96249Y204722
X93870Y199131
X56900Y197800
X97730Y188584
X98633Y78481
X95041Y78451
X91536Y78481
X97921Y-35764
X92921
X87921
X82921
X77921
X72921
X67921
X62921
X57921
X52921
X47921
X43521
X39121
X34721
X30321
X25921
X21521
X17121
X12721
X8321
X3921
X22964Y-40379
X8964
X3964
X22964Y-44779
X8964
X3964
X22964Y-49179
X18964
X13964
X8964
X3964
X22964Y-53579
X18964
X13964
X8964
X3964
X97921Y-58764
X92921
X87921
X82921
X77921
X72921
X67921
X62921
X57921
X52921
X47921
X43521
X39121
X34721
X30321
X25921
X21521
X17121
X12721
X8321
X3921
X102921
X107921
X112921
X117921
X122921
X127921
X132921
X137921
X142921
X147921
X152921
X157921
X162921
X167921
X172921
X177921
X182921
X187921
X192921
X197921
X102921Y-35764
X107921
X112921
X117921
X122921
X127921
X132921
X137921
X142921
X147921
X152921
X157921
X162921
X167921
X172921
X177921
X182921
X187921
X192921
X197921
X122044Y162340
X108174Y164127
X123624Y164600
X140200Y204400
X137300Y204500
X143900Y204600
X147500Y205500
X151000
X154500
X161216Y206933
X157800Y207300
X164300Y207870
X161216Y209533
X173300Y211900
X176300
X137615Y212039
X140889Y211972
X150600Y212900
X153200
X160800
X163400
X166000
X168600
X179300Y213208
X176300Y214500
X173300Y214800
X179300Y216108
X182300
X176300Y217308
X173300Y217700
X195300Y229250
X173400Y231400
X176508Y231609
X188300Y234000
X185250Y234250
X173400Y234300
X176400
X179400
X182400
X122231Y234716
X188200Y236800
X142425Y236943
X145025
X147625
X150225
X152825
X155425
X158025
X160625
X163225
X165825
X168425
X139800Y237000
X173400
X176400
X179400
X182400
X185250Y236950
X122632Y237816
X125564
X163225Y239543
X165825
X168425
X185250Y239850
X188100Y239800
X173400Y239900
X176400
X179400
X182400
X163225Y242143
X165825
X168425
X142371Y244384
X163225Y244743
X165825
X168425
X198200Y246500
Y249500
X195100Y252000
X198200Y252500
X169150Y255470
Y259470
X122231Y266716
X157633Y268727
X160233
X162833
X165433
X168033
X139815Y268974
X142466Y268982
X122531Y269816
X125463
X185768Y270065
X188475
X162833Y271327
X165433
X168033
X185754Y272689
X188510Y272666
X137900Y272800
X162833Y273927
X165433
X168033
X173835Y275204
X176835
X179835
X182935Y275604
X185735
X188535
X139683Y276174
X142700Y276200
X136729Y276386
X159983Y276507
X162833Y276527
X165433
X168033
X150700Y276800
X153300
X173835Y277804
X176835
X179835
X198082Y277995
X182935Y278204
X185735
X188600Y278300
X191400Y278400
X198182Y280995
X169150Y287600
Y291600
X172800Y295500
X175800
X181800
X184800
X190800
X193800
X178956Y295583
X187956
X196956
X172800Y298400
X175800
X178800
X181800
X184800
X187800
X122231Y298716
X142433Y301057
X145033
X147633
X150233
X152833
X155433
X158033
X160633
X163233
X165833
X168433
X172800Y301100
X175800
X178800
X181800
X184800
X187800
X122731Y301716
X125663
X139900Y302400
X160233Y303657
X163233
X165833
X168433
X172800Y304000
X175800
X178800
X181800
X184800
X187800
X160233Y306257
X163233
X165833
X168433
X187900Y306900
X190665Y306877
X197684Y307227
X160233Y308857
X163233
X165833
X168433
X190570Y309539
X197730Y309959
X169150Y319600
Y323600
X194792Y327643
X197792
X191792Y327743
X188654Y327973
X122231Y330716
X188654Y330973
X157745Y332800
X142465Y332940
X139866Y333016
X160501Y332965
X163101
X165701
X168301
X125500Y333500
X122731Y333916
X185630Y333923
X188630
X157518Y335391
X160274Y335556
X163101Y335565
X165701
X168301
X185300Y336900
X188300
X173300Y337000
X176300
X179300
X182300
X163101Y338165
X165701
X168301
X198119Y339710
X191300Y339800
X173300Y339900
X176300
X179300
X182300
X185300
X188300
X163101Y340765
X165701
X168301
X154200Y341100
X145200Y341300
X148200
X151000
X198223Y342430
X191300Y343248
X185300Y343348
X188300
X173300Y343448
X176300
X179300
X182300
X195233Y345402
X198233
Y348402
X195233Y351402
X198233
X169150Y351600
Y355600
X173424Y359621
X176424
X179424
X182424
X185424
X188424
X122331Y362716
X173471Y363281
X176471
X179471
X182471
X185471
X188471
X167700Y363900
X145033Y364457
X147833
X150633
X153433
X156233
X159033
X161833
X164633
X125600Y364900
X139767Y364883
X142421Y364908
X122600Y365500
X173400Y366787
X176400
X179400
X182400
X185400
X188400
X161833Y369657
X164633
X167433
X173400Y369787
X176400
X179400
X182400
X185400
X188400
X199900Y370400
X161933Y372357
X164733
X167533
X199900Y373400
X166340Y374785
X197411Y374812
X199754Y376090
X171158Y382768
X174750Y383308
X167670Y383993
X171158Y385768
X174750Y386308
X167670Y387993
X171158Y388768
X174750Y389308
X190100Y393000
X102456Y393756
X187100Y394000
X122231Y394716
X101000Y397200
X103700
X106400
X109100
X143073Y397194
X140475Y397310
X122000Y397600
X125300Y397700
X111561Y398819
X101000Y399900
X103700
X106400
X109100
X114084Y399937
X140218Y400163
X142818
X134929Y400296
X137529
X122840Y400827
X142863Y402829
X134992Y402900
X137619
X140219Y402894
X104517Y406279
X107571Y406291
X105761Y409208
X110519Y410307
X108010Y411479
X110199Y413852
X123648Y425041
X125328Y427269
X127932Y428571
X130613Y429647
X101606Y638753
X106006
X110406
X114806
X119206
X123606
X128006
X132406
X136806
X141206
X145606
X150006
X154406
X158806
X163206
X167606
X172006
X176406
X180806
X185206
X189606
X194006
X198406
X101621Y660756
X106021
X110421
X114821
X119221
X123621
X128021
X132421
X136821
X141221
X145621
X150021
X154421
X158821
X163221
X167621
X172021
X176421
X180821
X185221
X189621
X194021
X198421
X299621
X295221
X290821
X286421
X282021
X277621
X273221
X268821
X264421
X260021
X255621
X251221
X246821
X242421
X238021
X233621
X229221
X224821
X220421
X216021
X211621
X207221
X202821
X261125Y652784
X251213
X226500Y649900
X261125Y646784
X251213
X299606Y638753
X295206
X290806
X286406
X282006
X277606
X273206
X268806
X264406
X260006
X255606
X251206
X246806
X242406
X238006
X233606
X229206
X224806
X220406
X216006
X211606
X207206
X202806
X201045Y348449
X204060Y345527
X201045Y345449
X204060Y342527
X201163Y342476
X214000Y340900
X204163Y339476
X201163
X204177Y336728
X201177
X219000Y335900
X201177Y333728
X224000Y330900
X201177Y330728
X229100Y325900
X234000Y320900
X200251Y306548
X200947Y280933
X203947Y277933
X200947
X203847Y274933
X200847
X234501Y270392
X230800Y265200
X224390Y258920
X219500Y254500
X207200Y252500
X204200
X201200
X207200Y249500
X204200
X201200
X203900Y246500
X201100
X297921Y-35764
X292921
X287921
X282921
X277921
X272921
X267921
X262921
X257921
X252921
X247921
X242921
X237921
X232921
X227921
X222921
X217921
X212921
X207921
X202921
X297921Y-58764
X292921
X287921
X282921
X277921
X272921
X267921
X262921
X257921
X252921
X247921
X242921
X237921
X232921
X227921
X222921
X217921
X212921
X207921
X202921
X302921
X307921
X312921
X317921
X322921
X327921
X332921
X337921
X342921
X347921
X352921
X357921
X362921
X367921
X372921
X377921
X382921
X387921
X392921
X397921
X302921Y-35764
X307921
X312921
X317921
X322921
X327921
X332921
X337921
X342921
X347921
X352921
X357921
X362921
X367921
X372921
X377921
X382921
X387921
X392921
X397921
X380885Y270876
Y273876
X385945Y278480
X368094Y278904
X371094
X375294
X378294
X382494
X389694
X392694
X371094Y292904
X378294
X385494
X389528Y292910
X392694Y292904
X399894
X368116Y293087
X373736Y293068
X396897Y293058
X382625Y293207
X368094Y295904
X371094
X375294
X378294
X382494
X385494
X389694
X392694
X396894
X399894
X371237Y309846
X378577Y309795
X367914Y309910
X374994
X382497
X385494Y309904
X389502Y309910
X392694Y309904
X396709Y309910
X399894Y309904
X365693Y311893
X385494Y324173
X388394
X391144
X393894
X396894
X399894
X366822Y324459
X372391Y326746
X375223Y326798
X377894Y326777
X369748Y326902
X367121Y327057
X375848Y329512
X378785Y329580
X304006Y638753
X308406
X312806
X317206
X321606
X326006
X330406
X334806
X339206
X343606
X348006
X352406
X356806
X361206
X365606
X370006
X374406
X378806
X383206
X387606
X392006
X396406
X379561Y646508
X389473
X379561Y652508
X389473
X304021Y660756
X308421
X312821
X317221
X321621
X326021
X330421
X334821
X339221
X343621
X348021
X352421
X356821
X361221
X365621
X370021
X374421
X378821
X383221
X387621
X392021
X396421
X497621
X493221
X488821
X484421
X480021
X475621
X471221
X466821
X462421
X458021
X453621
X449221
X444821
X440421
X436021
X431621
X427221
X422821
X418421
X414021
X409621
X405221
X400821
X448593Y652514
X438681
X448593Y646514
X438681
X497606Y638753
X493206
X488806
X484406
X480006
X475606
X471206
X466806
X462406
X458006
X453606
X449206
X444806
X440406
X436006
X431606
X427206
X422806
X418406
X414006
X409606
X405206
X400806
X451267Y324476
X435894Y324173
X432894
X428694
X425694
X421494
X418494
X414894
X411894
X408894
X405894
X402894
X448694Y323949
X446094Y323904
X407094Y309904
X404117Y309910
X451816Y295904
X443094
X440094
X435894
X432894
X428694
X425694
X421494
X418494
X414294
X411294
X407094
X404094
X454922Y295841
X446383
X404266Y293030
X407094Y292904
X449148Y292841
X446209Y292842
X455226Y291686
X451675Y291739
X443094Y278904
X440094
X435894Y278938
X432894Y278910
X428694
X425694
X421523Y278944
X418523Y278910
X414207
X411288
X407094
X404094
X400842Y278914
X420188Y264899
X417190
X414188
X411188
X407594
X404594
X436329Y264826
X425911Y264710
X423092Y264697
X432643Y264508
X436519Y262232
X497921Y-35764
X492921
X487921
X482921
X477921
X472921
X467921
X462921
X457921
X452921
X447921
X442921
X437921
X432921
X427921
X422921
X417921
X412921
X407921
X402921
X497921Y-58764
X492921
X487921
X482921
X477921
X472921
X467921
X462921
X457921
X452921
X447921
X442921
X437921
X432921
X427921
X422921
X417921
X412921
X407921
X402921
X502921
X507921
X512921
X517921
X522921
X527921
X532921
X537921
X542921
X547921
X552921
X557921
X562921
X567921
X572921
X577921
X582921
X587921
X592921
X597921
X502921Y-35764
X507921
X512921
X517921
X522921
X527921
X532921
X537921
X542921
X547921
X552921
X557921
X562921
X567921
X572921
X577921
X582921
X587921
X592921
X597921
X502006Y638753
X506406
X510806
X515206
X519606
X524006
X528406
X532806
X537206
X541606
X546006
X550406
X554806
X559206
X563606
X568006
X572406
X576806
X581206
X585606
X590006
X594406
X598806
X567029Y646238
X576941
X567029Y652238
X576941
X502021Y660756
X506421
X510821
X515221
X519621
X524021
X528421
X532821
X537221
X541621
X546021
X550421
X554821
X559221
X563621
X568021
X572421
X576821
X581221
X585621
X590021
X594421
X598821
X695621
X691221
X686821
X682421
X678021
X673621
X669221
X664821
X660421
X656021
X651621
X647221
X642821
X638421
X634021
X629621
X625221
X620821
X616421
X612021
X607621
X603221
X601500Y649500
X695606Y638753
X691206
X686806
X682406
X678006
X673606
X669206
X664806
X660406
X656006
X651606
X647206
X642806
X638406
X634006
X629606
X625206
X620806
X616406
X612006
X607606
X603206
X690966Y624130
X681714Y620682
X673864Y619643
X667566Y610630
X673864Y601615
X681713Y600577
X690966Y597130
X605176Y487581
X632771Y473269
X641107Y471989
X629359Y469583
X634033Y467638
X628589Y463649
X695790Y351300
X641541Y243828
Y241228
Y238628
Y236028
X650700Y231800
X647600
X644500
X641600
X637001Y229937
X650700Y229200
X647600
X644500
X641600
X637001Y227337
X650700Y226600
X647600
X644500
X641600
X653750Y225500
X637001Y224737
X650700Y224000
X647600
X644500
X641600
X637001Y222137
X641600Y221400
X690966Y5626
X681714Y2178
X673864Y1139
X667566Y-7874
X673864Y-16889
X681713Y-17927
X690966Y-21374
X697921Y-35764
X692921
X687921
X682921
X677921
X672921
X667921
X662921
X657921
X652921
X647921
X642921
X637921
X632921
X627921
X622921
X617921
X612921
X607921
X602921
X697921Y-58764
X692921
X687921
X682921
X677921
X672921
X667921
X662921
X657921
X652921
X647921
X642921
X637921
X632921
X627921
X622921
X617921
X612921
X607921
X602921
X702921
X707921
X712921
X717921
X722921
X727921
X732921
X737921
X742921
X747921
X752921
X757921
X762921
X767921
X772921
X777921
X782921
X787921
X792921
X797921
X702921Y-35764
X707921
X712921
X717921
X722921
X727921
X732921
X737921
X742921
X747921
X752921
X757921
X762921
X767921
X772921
X777921
X782921
X787921
X792921
X797921
X700517Y-17425
X704466Y-7874
X700525Y1668
X792514Y201290
X797717Y201907
X788522Y204343
X791122Y204339
X785920Y204763
X786300Y207400
X786674Y211463
X789274
X791874
X794474
X770632Y234833
X789432Y236947
X792032Y237000
X794632
X797232
X799832
X770965Y237519
X773800Y237700
X768382Y237861
X787100Y241100
X787200Y244200
X791000Y244400
X793600
X769637Y266647
X772630Y266810
X789591Y269101
X792191
X770485Y269489
X773419Y270414
X787200Y271900
X789400Y273700
X787200Y276400
X789800
X792400
X769440Y298735
X772400Y299400
X775200Y301200
X789500
X792100
X794700
X797300
X799900
X768290Y301780
X770900Y301800
X787100Y303900
X788600Y306100
X787000Y308300
X789900Y308400
X792900
X771730Y330665
X794600Y332600
X744698Y332816
X791879Y332798
X772949Y333009
X775732Y332989
X770278Y333272
X744698Y335516
X747498
X750298
X744698Y338316
X747498
X750298
X753098
X790300Y340300
X787400Y340400
X793000
X744698Y344833
X747498
X750298
X744698Y347833
X747498
X750298
X769440Y363810
X745073Y364009
X747673
X750273
X795310Y364721
X792610Y364821
X789860Y364947
X772290Y365020
X775070Y365070
X769380Y366440
X744973Y366909
X747573
X750173
X790900Y372300
X785400Y372400
X788300
X743500Y374000
X747000
X750500
X754000
X757500
X741774Y376463
X753874Y379863
X743500Y380000
X747000
X750500
X700204Y384010
X711173Y384312
X702973Y384412
X705673
X708373
X743500Y386000
X747000
X750500
X754000
X700204Y386610
X702973Y387012
X705673
X708373
X711173
X700391Y389737
X703160Y390139
X706164Y390143
X708975Y390174
X711575Y390150
X700291Y392637
X703160Y392939
X706164Y393143
X708975Y393174
X711575Y393150
X700458Y395503
X703169Y395986
X706164Y396143
X711575Y396150
X769770Y396070
X708975Y396174
X766860Y396240
X789600Y396809
X792238Y396753
X775420Y397110
X772742Y397209
X789400Y399409
X792000
X700517Y601079
X704466Y610630
X700525Y620172
X700006Y638753
X704406
X708806
X713206
X717606
X722006
X726406
X730806
X735206
X739606
X744006
X748406
X752806
X757206
X761606
X766006
X770406
X774806
X779206
X783606
X788006
X792406
X796806
X700021Y660756
X704421
X708821
X713221
X717621
X722021
X726421
X730821
X735221
X739621
X744021
X748421
X752821
X757221
X761621
X766021
X770421
X774821
X779221
X783621
X788021
X792421
X796821
X898021
X893621
X889221
X884821
X880421
X876021
X871621
X867221
X862821
X858421
X854021
X849621
X845221
X840821
X836421
X832021
X827621
X823221
X818821
X814421
X810021
X805621
X801221
X898006Y638753
X893606
X889206
X884806
X880406
X876006
X871606
X867206
X862806
X858406
X854006
X849606
X845206
X840806
X836406
X832006
X827606
X823206
X818806
X814406
X810006
X805606
X801206
X811515Y397289
X808915
X813648Y395557
X814877Y393138
X815472Y390442
X823218Y385950
X820218
X826097Y385923
X826216Y383108
X823218Y382950
X820218
X851208Y378668
X848608
X846008
X851208Y376068
X848608
X846008
X816591Y375057
X848932Y373257
X851727Y373197
X816591Y372457
X813991
X811391
X816591Y369857
X813991
X811391
X834658Y369463
X832058
X829458
X826858
X824258
X821658
X834658Y366863
X832058
X829458
X826858
X824258
X821658
X837363Y366829
X815759Y364575
X813159
X810559
X807959
X805359
X802759
X834089Y362782
X831089
X828089
X825089
X822089
X816900Y361400
X834089Y359841
X831089
X828089
X825089
X822089Y359782
X816672Y358809
X816593Y356210
X856982Y344327
X853982
X850982
X847982
X844350Y344000
X840262Y343011
X837382Y342877
X834482Y342827
X831482
X828482
X825482
X822482
X856982Y341327
X853982
X850982
X847982
X862008Y341100
X840282Y340227
X816991Y339957
X814391
X811791
X837382Y339877
X834482Y339827
X831482
X828482
X825482
X822482
X856982Y338327
X853982
X850982
X847982
X840382Y337427
X816991Y337357
X814391
X811791
X837382Y337077
X834482Y337027
X831482
X828482
X825482
X822482
X867008Y336100
X857075Y335405
X854075
X851075
X816991Y334757
X814391
X811791
X872008Y331100
X877008Y326100
X816938Y323888
Y319888
X817100Y317000
X856682Y314627
X853682
X850682
X847682
X844300Y312450
X856682Y312027
X853682
X850682
X847682
X856682Y309327
X853682
X850682
X847682
X817191Y308957
X814591
X811991
X856682Y306727
X853682
X850682
X847682
X817191Y306357
X814591
X811991
X837782Y303927
X834682
X831682
X828682
X825682
X822682
X817191Y303757
X814591
X811991
X834682Y301227
X831682
X828682
X825682
X822682
X818100Y301200
X815500
X812900
X810300
X807700
X805100
X802500
X837782Y301027
X834682Y298527
X831682
X828682
X825682
X822682
X837782Y298127
X825682Y295527
X822682
X857382Y282327
X854382
X851382
X848382
X844400Y280500
X840064Y280110
X837264
X834464
X831464
X828464
X825464
X822464
X857382Y279727
X854382
X851382
X848382
X840064Y277510
X837264
X834464
X831464
X828464
X825464
X822464
X857382Y277027
X854382
X851382
X848382
X817491Y276857
X814891
X812291
X804591Y276557
X801991
X837264Y274910
X834464
X831464
X828464
X825464
X822464
X857382Y274427
X854382
X851382
X848382
X889586Y274278
X817491Y274257
X814891
X812291
X817491Y271657
X814891
X812291
X884586Y269278
X817491Y269057
X814891
X812291
X879586Y264278
X874586Y259278
X817000Y257700
Y255100
X869586Y254278
X857282Y254327
X854282
X851282
X848282
X817000Y252500
X845050Y252250
X857282Y251727
X854282
X851282
X848282
X857282Y249027
X854282
X851282
X848282
X857282Y246427
X854282
X851282
X848282
X817183Y244843
X814583
X811983
X817183Y242243
X814583
X811983
X834682Y239627
X831682
X828682
X825682
X822682
X817183Y239643
X814583
X811983
X837500Y239500
X831682Y237027
X828682
X825682
X822682
X818032Y237000
X815432
X812832
X810232
X807632
X805032
X802432
X834682Y236877
X837500Y236650
X831682Y234327
X828682
X825682
X822682
X816800Y234300
X840155Y234245
X834700Y234200
X837500Y234050
X825313Y231753
X828180Y231748
X822682Y231727
X816900Y230900
X845050Y229400
X821775Y217617
X824446Y217476
X827322Y217430
X816900Y216300
X824072Y214865
X821466Y214925
X832276Y214754
X826700Y214802
X829327Y214740
X803200Y213100
X800600
X816874Y212863
X814274
X811674
X808818Y211179
X808618Y208579
X814849Y205001
X808165Y203529
X803134Y202969
X818960Y202230
X897921Y-35764
X892921
X887921
X882921
X877921
X872921
X867921
X862921
X857921
X852921
X847921
X842921
X837921
X832921
X827921
X822921
X817921
X812921
X807921
X802921
X897921Y-58764
X892921
X887921
X882921
X877921
X872921
X867921
X862921
X857921
X852921
X847921
X842921
X837921
X832921
X827921
X822921
X817921
X812921
X807921
X802921
X902921
X907921
X912921
X917921
X922921
X927921
X932921
X937921
X942921
X947921
X952921
X957921
X962921
X967921
X972921
X977921
X982921
X987921
X992921
X997921
X902921Y-35764
X907921
X912921
X917921
X922921
X927921
X932921
X937921
X942921
X947921
X952921
X957921
X962921
X967921
X972921
X977921
X982921
X987921
X992921
X997921
X902406Y638753
X906806
X911206
X915606
X920006
X924406
X928806
X933206
X937606
X942006
X946406
X950806
X955206
X959606
X964006
X968406
X972806
X977206
X981606
X986006
X990406
X994806
X999206
X941883Y646234
X951795
X917100Y649300
X941883Y652234
X951795
X902421Y660756
X906821
X911221
X915621
X920021
X924421
X928821
X933221
X937621
X942021
X946421
X950821
X955221
X959621
X964021
X968421
X972821
X977221
X981621
X986021
X990421
X994821
X999221
X1096021
X1091621
X1087221
X1082821
X1078421
X1074021
X1069621
X1065221
X1060821
X1056421
X1052021
X1047621
X1043221
X1038821
X1034421
X1030021
X1025621
X1021221
X1016821
X1012421
X1008021
X1003621
X1096006Y638753
X1091606
X1087206
X1082806
X1078406
X1074006
X1069606
X1065206
X1060806
X1056406
X1052006
X1047606
X1043206
X1038806
X1034406
X1030006
X1025606
X1021206
X1016806
X1012406
X1008006
X1003606
X1086126Y338758
X1083301Y338841
X1071192Y338673
X1068192
X1063992
X1060992
X1056792
X1080282Y338533
X1077282
X1083220Y324174
X1079020
X1076020
X1071820
X1068820
X1065220
X1062220
X1059220
X1056220
X1053220
X1050220
X1047220
X1044220
X1041470
X1038720
X1035820
X1098402Y324017
X1095402Y323904
X1015293Y311955
X1056747Y309904
X1053594Y309910
X1049547Y309904
X1046612Y309910
X1042347Y309904
X1039383Y309910
X1035147Y309904
X1032042Y309910
X1024140
X1017083
X1028136Y309815
X1021065Y309759
X1092567Y295859
X1089567
X1085367
X1082367
X1078167
X1075167
X1070967
X1067967
X1063767
X1060767
X1056567
X1053567
X1049367
X1046367
X1042167
X1039167
X1034967
X1031967
X1027767
X1024767
X1020567
X1017567
X1098567Y295841
X1095567
X1056702Y292904
X1053684Y292910
X1049502Y292904
X1046276Y292910
X1042302Y292904
X1039182Y292919
X1035102Y292904
X1031953Y292910
X1027902Y292904
X1024994Y292918
X1020702Y292904
X1017630Y292910
X1098756Y292841
X1095756
X1049867Y278999
X1089702Y278904
X1085518Y278910
X1082330
X1078302
X1075302
X1070926
X1067783
X1063652
X1060958
X1056602
X1053459
X1042302Y278904
X1039302
X1032102
X1027902
X1024902
X1020702
X1017702
X1035814Y278775
X1030489Y273889
Y270889
X1073200Y264991
X1086000Y264900
X1070300
X1057202Y264899
X1054202
X1075865Y264766
X1063402Y264799
X1060402
X1066300Y264700
X1082432Y264620
X1086061Y262300
X1097921Y-35764
X1092921
X1087921
X1082921
X1077921
X1072921
X1067921
X1062921
X1057921
X1052921
X1047921
X1042921
X1037921
X1032921
X1027921
X1022921
X1017921
X1012921
X1007921
X1002921
X1097921Y-58764
X1092921
X1087921
X1082921
X1077921
X1072921
X1067921
X1062921
X1057921
X1052921
X1047921
X1042921
X1037921
X1032921
X1027921
X1022921
X1017921
X1012921
X1007921
X1002921
X1102921
X1107921
X1112921
X1117921
X1122921
X1127921
X1132921
X1137921
X1142921
X1147921
X1152921
X1157921
X1162921
X1167921
X1172921
X1177921
X1182921
X1187921
X1192921
X1197921
X1102921Y-35764
X1107921
X1112921
X1117921
X1122921
X1127921
X1132921
X1137921
X1142921
X1147921
X1152921
X1157921
X1162921
X1167921
X1172921
X1177921
X1182921
X1187921
X1192921
X1197921
X1104256Y291841
X1101615Y292447
X1104221Y295696
X1101567Y295859
X1112490Y312723
X1112515Y315369
X1101200Y324013
X1100406Y638753
X1104806
X1109206
X1113606
X1118006
X1122406
X1126806
X1131206
X1135606
X1140006
X1144406
X1148806
X1153206
X1157606
X1162006
X1166406
X1170806
X1175206
X1179606
X1184006
X1188406
X1192806
X1197206
X1196198Y646206
Y652206
X1100421Y660756
X1104821
X1109221
X1113621
X1118021
X1122421
X1126821
X1131221
X1135621
X1140021
X1144421
X1148821
X1153221
X1157621
X1162021
X1166421
X1170821
X1175221
X1179621
X1184021
X1188421
X1192821
X1197221
X1298421
X1294021
X1289621
X1285221
X1280821
X1276421
X1272021
X1267621
X1263221
X1258821
X1254421
X1250021
X1245621
X1241221
X1236821
X1232421
X1228021
X1223621
X1219221
X1214821
X1210421
X1206021
X1201621
X1265293Y652264
X1255381
X1206110Y652206
X1265293Y646264
X1255381
X1206110Y646206
X1298406Y638753
X1294006
X1289606
X1285206
X1280806
X1276406
X1272006
X1267606
X1263206
X1258806
X1254406
X1250006
X1245606
X1241206
X1236806
X1232406
X1228006
X1223606
X1219206
X1214806
X1210406
X1206006
X1201606
X1297921Y-35764
X1292921
X1287921
X1282921
X1277921
X1272921
X1267921
X1262921
X1257921
X1252921
X1247921
X1242921
X1237921
X1232921
X1227921
X1222921
X1217921
X1212921
X1207921
X1202921
X1297921Y-58764
X1292921
X1287921
X1282921
X1277921
X1272921
X1267921
X1262921
X1257921
X1252921
X1247921
X1242921
X1237921
X1232921
X1227921
X1222921
X1217921
X1212921
X1207921
X1202921
X1302921
X1307921
X1312921
X1317921
X1322921
X1327921
X1332921
X1337921
X1342921
X1347921
X1352921
X1357921
X1362921
X1367921
X1372921
X1377921
X1382921
X1387921
X1392921
X1397921
X1302921Y-35764
X1307921
X1312921
X1317921
X1322921
X1327921
X1332921
X1337921
X1342921
X1347921
X1352921
X1357921
X1362921
X1377921
X1382921
X1387921
X1392921
X1397921
X1395913Y-7874
Y610630
X1302806Y638753
X1307206
X1311606
X1316006
X1320406
X1324806
X1329206
X1333606
X1338006
X1342406
X1346806
X1351206
X1355606
X1360006
X1364406
X1368806
X1373206
X1377606
X1382006
X1386906Y638853
X1391306
X1395706
X1302821Y660756
X1307221
X1311621
X1316021
X1320421
X1324821
X1329221
X1333621
X1338021
X1342421
X1346821
X1351221
X1355621
X1360021
X1364421
X1368821
X1373221
X1377621
X1382021
X1386921Y660856
X1391321
X1395721
X1496921
X1492521
X1488121
X1483721
X1479321
X1474921
X1470521
X1466121
X1461721
X1457321
X1452921
X1448521
X1444121
X1439721
X1435321
X1430921
X1426521
X1422121
X1417721
X1413321
X1408921
X1404521
X1400121
X1496906Y638853
X1492506
X1488106
X1483706
X1479306
X1474906
X1470506
X1466106
X1461706
X1457306
X1452906
X1448506
X1444106
X1439706
X1435306
X1430906
X1426506
X1422106
X1417706
X1413306
X1408906
X1404506
X1400106
X1419313Y624130
X1410061Y620682
X1428872Y620172
X1402211Y619643
X1432813Y610630
X1402211Y601615
X1428864Y601079
X1410060Y600577
X1419313Y597130
X1457300Y563900
X1454600
X1451900
X1449300
X1446600
X1473018Y562003
X1497918Y561872
X1470314Y561923
X1467714Y561896
X1495187Y561842
X1492187
X1463369Y561763
X1489316Y561742
X1456080Y547540
X1453166Y547481
X1495130Y545910
X1492130
X1497866Y545797
X1452392Y544998
X1431664Y190213
X1419313Y5626
X1410061Y2178
X1428872Y1668
X1402211Y1139
X1432813Y-7874
X1402211Y-16889
X1428864Y-17425
X1410060Y-17927
X1419313Y-21374
X1497921Y-35764
X1492921
X1487921
X1482921
X1477921
X1472921
X1467921
X1462921
X1457921
X1452921
X1447921
X1442921
X1437921
X1432921
X1427921
X1422921
X1417921
X1412921
X1407921
X1402921
X1497921Y-58764
X1492921
X1487921
X1482921
X1477921
X1472921
X1467921
X1462921
X1457921
X1452921
X1447921
X1442921
X1437921
X1432921
X1427921
X1422921
X1417921
X1412921
X1407921
X1402921
X1502921
X1507921
X1512921
X1517921
X1522921
X1527921
X1532921
X1537921
X1542921
X1547921
X1552921
X1557921
X1562921
X1567921
X1572921
X1577921
X1582921
X1587921
X1592921
X1597921
X1502921Y-35764
X1507921
X1512921
X1517921
X1522921
X1527921
X1532921
X1537921
X1542921
X1547921
X1552921
X1557921
X1562921
X1567921
X1572921
X1577921
X1582921
X1587921
X1592921
X1597921
X1567425Y144373
X1514372Y243361
X1514370Y246016
X1514372Y248616
X1591598Y257028
X1586399Y257099
X1588999Y257104
X1583047Y257171
X1586430Y259824
X1589030Y259807
X1591628Y259924
X1583078Y260122
X1570020Y295340
X1534897Y559808
X1526586Y559860
X1529286
X1531986
X1538385Y560978
X1500530Y561872
X1524538Y562286
X1527285Y562386
X1529985
X1532685
X1535385
X1541267Y563185
X1543967
X1546795Y563316
X1549395Y563541
X1538331Y563913
X1541080Y565859
X1544080
X1546825Y565986
X1549425Y566211
X1546685Y568656
X1544080Y568859
X1549285Y568881
X1501706Y638753
X1506106
X1510506
X1514906
X1519306
X1523706
X1528106
X1532506
X1536906
X1541306
X1545706
X1550106
X1555106
X1560106
X1565106
X1570106
X1575106
X1580106
X1585106
X1590106
X1595106
X1550121Y643156
X1555121
X1560121
X1565121
X1570121
X1575121
X1580121
X1585121
X1590121
X1595121
X1509696Y646236
X1519608
X1550121Y647556
X1555121
X1560121
X1565121
X1570121
X1575121
X1580121
X1585121
X1590121
X1595121
X1550121Y651956
X1555121
X1560121
X1565121
X1570121
X1575121
X1580121
X1585121
X1590121
X1595121
X1509696Y652236
X1519608
X1550121Y656356
X1555121
X1560121
X1565121
X1570121
X1575121
X1580121
X1585121
X1590121
X1595121
X1501721Y660756
X1506121
X1510521
X1514921
X1519321
X1523721
X1528121
X1532521
X1536921
X1541321
X1545721
X1550121
X1555121
X1560121
X1565121
X1570121
X1575121
X1580121
X1585121
X1590121
X1595121
X1695121
X1690121
X1685121
X1680121
X1675121
X1670121
X1665121
X1660121
X1655121
X1650121
X1645121
X1640121
X1635121
X1630121
X1625121
X1620121
X1615121
X1610121
X1605121
X1600121
X1695121Y656356
X1690121
X1685121
X1680121
X1675121
X1670121
X1665121
X1660121
X1655121
X1650121
X1645121
X1640121
X1635121
X1630121
X1625121
X1620121
X1615121
X1610121
X1605121
X1600121
X1695121Y651956
X1690121
X1685121
X1680121
X1675121
X1670121
X1665121
X1660121
X1655121
X1650121
X1645121
X1640121
X1635121
X1630121
X1625121
X1620121
X1615121
X1610121
X1605121
X1600121
X1695121Y647556
X1690121
X1685121
X1680121
X1675121
X1670121
X1665121
X1660121
X1655121
X1650121
X1645121
X1640121
X1635121
X1630121
X1625121
X1620121
X1615121
X1610121
X1605121
X1600121
X1695121Y643156
X1690121
X1685121
X1680121
X1675121
X1670121
X1665121
X1660121
X1655121
X1650121
X1645121
X1640121
X1635121
X1630121
X1625121
X1620121
X1615121
X1610121
X1605121
X1600121
X1695106Y638753
X1690106
X1685106
X1680106
X1675106
X1670106
X1665106
X1660106
X1655106
X1650106
X1645106
X1640106
X1635106
X1630106
X1625106
X1620106
X1615106
X1610106
X1605106
X1600106
X1608280Y249234
X1608099Y197125
X1697921Y-35764
X1692921
X1687921
X1682921
X1677921
X1672921
X1667921
X1662921
X1657921
X1652921
X1647921
X1642921
X1637921
X1632921
X1627921
X1622921
X1617921
X1612921
X1607921
X1602921
X1697921Y-40764
X1692921
X1687921
X1682921
X1677921
X1672921
X1697921Y-45764
X1692921
X1687921
X1682921
X1677921
X1672921
X1697921Y-50764
X1692921
X1687921
X1682921
X1677921
X1672921
X1697921Y-54764
X1692921
X1687921
X1682921
X1677921
X1672921
X1697921Y-58764
X1692921
X1687921
X1682921
X1677921
X1672921
X1667921
X1662921
X1657921
X1652921
X1647921
X1642921
X1637921
X1632921
X1627921
X1622921
X1617921
X1612921
X1607921
X1602921
X1702921
X1707921
X1712921
X1717921
X1722921
X1727921
X1732921
X1737921
X1742921
X1747921
X1752921
X1757921
X1762921
X1767921
X1772921
X1777921
X1782921
X1787921
X1792921
X1797921
X1702921Y-54764
X1707921
X1712921
X1717921
X1722921
X1727921
X1732921
X1737921
X1742921
X1747921
X1752921
X1757921
X1762921
X1767921
X1772921
X1777921
X1782921
X1787921
X1792921
X1797921
X1702921Y-50764
X1707921
X1712921
X1717921
X1722921
X1727921
X1732921
X1737921
X1742921
X1747921
X1752921
X1757921
X1762921
X1767921
X1772921
X1777921
X1782921
X1787921
X1792921
X1797921
X1702921Y-45764
X1707921
X1712921
X1717921
X1722921
X1727921
X1732921
X1737921
X1742921
X1747921
X1752921
X1757921
X1762921
X1767921
X1772921
X1777921
X1782921
X1787921
X1792921
X1797921
X1702921Y-40764
X1707921
X1712921
X1717921
X1722921
X1727921
X1732921
X1737921
X1742921
X1747921
X1752921
X1757921
X1762921
X1767921
X1772921
X1777921
X1782921
X1787921
X1792921
X1797921
X1702921Y-35764
X1707921
X1712921
X1717921
X1722921
X1727921
X1732921
X1737921
X1742921
X1747921
X1752921
X1757921
X1762921
X1767921
X1772921
X1777921
X1782921
X1787921
X1792921
X1797921
X1794992Y61342
X1797664Y61334
X1792382Y61363
X1792363Y64182
X1794973Y64161
X1797645Y64153
X1793268Y162774
X1793205Y165531
X1724800Y211300
X1727600
X1758324Y232657
X1739044Y237284
X1741668Y237314
X1744308Y237295
X1747227Y237314
X1735000Y250000
X1738000
X1741000
X1758000
X1728139Y496807
X1725566Y497186
X1704596Y498876
X1723591Y499135
X1702005Y499163
X1725600Y501000
X1704544Y501627
X1701874Y501795
X1700106Y638753
X1705106
X1710106
X1715106
X1720106
X1725106
X1730106
X1735106
X1740106
X1745106
X1750106
X1755106
X1760106
X1765106
X1770106
X1775106
X1780106
X1785106
X1790106
X1795106
X1700121Y643156
X1705121
X1710121
X1715121
X1720121
X1725121
X1730121
X1735121
X1740121
X1745121
X1750121
X1755121
X1760121
X1765121
X1770121
X1775121
X1780121
X1785121
X1790121
X1795121
X1700121Y647556
X1705121
X1710121
X1715121
X1720121
X1725121
X1730121
X1735121
X1740121
X1745121
X1750121
X1755121
X1760121
X1765121
X1770121
X1775121
X1780121
X1785121
X1790121
X1795121
X1700121Y651956
X1705121
X1710121
X1715121
X1720121
X1725121
X1730121
X1735121
X1740121
X1745121
X1750121
X1755121
X1760121
X1765121
X1770121
X1775121
X1780121
X1785121
X1790121
X1795121
X1700121Y656356
X1705121
X1710121
X1715121
X1720121
X1725121
X1730121
X1735121
X1740121
X1745121
X1750121
X1755121
X1760121
X1765121
X1770121
X1775121
X1780121
X1785121
X1790121
X1795121
X1700121Y660756
X1705121
X1710121
X1715121
X1720121
X1725121
X1730121
X1735121
X1740121
X1745121
X1750121
X1755121
X1760121
X1765121
X1770121
X1775121
X1780121
X1785121
X1790121
X1795121
X1895121
X1890121
X1885121
X1880121
X1875121
X1870121
X1865121
X1860121
X1855121
X1850121
X1845121
X1840121
X1835121
X1830121
X1825121
X1820121
X1815121
X1810121
X1805121
X1800121
X1895121Y656356
X1890121
X1885121
X1880121
X1875121
X1870121
X1865121
X1860121
X1855121
X1850121
X1845121
X1840121
X1835121
X1830121
X1825121
X1820121
X1815121
X1810121
X1805121
X1800121
X1895121Y651956
X1890121
X1885121
X1880121
X1875121
X1870121
X1865121
X1860121
X1855121
X1850121
X1845121
X1840121
X1835121
X1830121
X1825121
X1820121
X1815121
X1810121
X1805121
X1800121
X1895121Y647556
X1890121
X1885121
X1880121
X1875121
X1870121
X1865121
X1860121
X1855121
X1850121
X1845121
X1840121
X1835121
X1830121
X1825121
X1820121
X1815121
X1810121
X1805121
X1800121
X1895121Y643156
X1890121
X1885121
X1880121
X1875121
X1870121
X1865121
X1860121
X1855121
X1850121
X1845121
X1840121
X1835121
X1830121
X1825121
X1820121
X1815121
X1810121
X1805121
X1800121
X1895106Y638753
X1890106
X1885106
X1880106
X1875106
X1870106
X1865106
X1860106
X1855106
X1850106
X1845106
X1840106
X1835106
X1830106
X1825106
X1820106
X1815106
X1810106
X1805106
X1800106
X1868132Y624130
X1858880Y620682
X1877691Y620172
X1851030Y619643
X1881632Y610630
X1844732
X1851030Y601615
X1877683Y601079
X1858879Y600577
X1868132Y597130
X1892118Y454383
X1888968
X1882669Y454368
X1886200Y454280
X1895275Y448054
X1892126
X1888976
X1886330Y448010
X1880633Y263109
X1883723Y263029
X1880633Y260109
X1883723Y260029
X1832000Y165800
X1828390Y165600
X1852654Y164624
X1847654
X1836200Y153424
X1833000
X1833600Y145900
X1831148Y144592
X1814667Y94868
X1811967
X1809267
X1814667Y92168
X1811967
X1809267
X1814667Y89468
X1811967
X1809267
X1814667Y86868
X1811967
X1809267
X1823188Y79943
X1820488
X1842783Y77599
X1839985Y77522
X1837077Y77429
X1823155Y77329
X1820455
X1844048Y75184
X1846667Y75106
X1841250Y75107
X1838342Y75014
X1835714Y75029
X1831460Y73300
X1845165Y72692
X1842515
X1839865
X1837129Y72526
X1824060Y72460
X1821070Y72480
X1831460Y70600
X1834059Y70501
X1845165Y70042
X1842515
X1839865
X1837161Y69926
X1824180Y69460
X1821270Y69470
X1849325Y67362
X1846675
X1844025
X1813363Y62172
X1810563
X1807891Y62180
X1805281Y62201
X1823830Y60700
X1813393Y59493
X1810693
X1808021Y59501
X1805411Y59522
X1824410Y58030
X1813278Y56866
X1810578
X1807916Y56895
X1805282Y56880
X1826900Y56500
X1824350Y55180
X1825930Y52900
X1862636Y26780
X1859036
X1855436
X1851936
X1835921Y26818
X1832771
X1838700Y26638
X1847797Y26331
X1864020Y24470
X1851040Y24130
X1860981Y23894
X1857381
X1853781
X1865450Y22000
X1847564Y21636
X1838100Y21500
X1835121Y21532
X1832071
X1862936Y21118
X1859436
X1855836
X1852236
X1868132Y5626
X1858880Y2178
X1877691Y1668
X1851030Y1139
X1881632Y-7874
X1844732
X1851030Y-16889
X1877683Y-17425
X1858879Y-17927
X1868132Y-21374
X1897921Y-35764
X1892921
X1887921
X1882921
X1877921
X1872921
X1867921
X1862921
X1857921
X1852921
X1847921
X1842921
X1837921
X1832921
X1827921
X1822921
X1817921
X1812921
X1807921
X1802921
X1897921Y-40764
X1892921
X1887921
X1882921
X1877921
X1872921
X1867921
X1862921
X1857921
X1852921
X1847921
X1842921
X1837921
X1832921
X1827921
X1822921
X1817921
X1812921
X1807921
X1802921
X1897921Y-45764
X1892921
X1887921
X1882921
X1877921
X1872921
X1867921
X1862921
X1857921
X1852921
X1847921
X1842921
X1837921
X1832921
X1827921
X1822921
X1817921
X1812921
X1807921
X1802921
X1897921Y-50764
X1892921
X1887921
X1882921
X1877921
X1872921
X1867921
X1862921
X1857921
X1852921
X1847921
X1842921
X1837921
X1832921
X1827921
X1822921
X1817921
X1812921
X1807921
X1802921
X1897921Y-54764
X1892921
X1887921
X1882921
X1877921
X1872921
X1867921
X1862921
X1857921
X1852921
X1847921
X1842921
X1837921
X1832921
X1827921
X1822921
X1817921
X1812921
X1807921
X1802921
X1897921Y-58764
X1892921
X1887921
X1882921
X1877921
X1872921
X1867921
X1862921
X1857921
X1852921
X1847921
X1842921
X1837921
X1832921
X1827921
X1822921
X1817921
X1812921
X1807921
X1802921
X1902921
X1907921
X1912921
X1917921
X1922921
X1927921
X1932921
X1937921
X1942921
X1947921
X1952921
X1957921
X1962921
X1967921
X1902921Y-54764
X1907921
X1912921
X1917921
X1922921
X1927921
X1932921
X1937921
X1942921
X1947921
X1952921
X1957921
X1962921
X1967921
X1902921Y-50764
X1907921
X1912921
X1917921
X1922921
X1927921
X1932921
X1937921
X1942921
X1947921
X1952921
X1957921
X1962921
X1967921
X1902921Y-45764
X1907921
X1912921
X1917921
X1922921
X1927921
X1932921
X1937921
X1942921
X1947921
X1962921
X1967921
X1902921Y-40764
X1907921
X1912921
X1917921
X1922921
X1927921
X1932921
X1937921
X1942921
X1947921
X1962921
X1967921
X1902921Y-35764
X1907921
X1912921
X1917921
X1922921
X1927921
X1932921
X1937921
X1942921
X1947921
X1952921
X1957921
X1962921
X1967921
X1930150Y70447
X1932950
X1935550
X1938150
X1940950Y70547
X1943750
X1929961Y73247
X1935350
X1937950
X1932730Y73310
X1940750Y73347
X1943550
X1946350Y73447
X1948951Y73448
X1936706Y75987
X1939470Y76000
X1942390Y76040
X1945020Y76060
X1954271Y80449
X1907428Y91133
X1904678Y93845
X1907385Y93926
X1904742Y96552
X1907448Y96615
X1908400Y101010
X1937100Y146900
X1910219Y223358
X1910153Y226090
X1938127Y228016
X1940847Y227984
X1966300Y229600
X1969500
X1914037Y243646
X1910999Y467000
X1914173
X1917298Y466999
X1900106Y638753
X1905106
X1910106
X1915106
X1920106
X1925106
X1930106
X1935106
X1940106
X1945106
X1950106
X1955106
X1960106
X1965106
X1970106
X1900121Y643156
X1905121
X1910121
X1915121
X1920121
X1935121
X1940121
X1945121
X1965121
X1970121
X1900121Y647556
X1905121
X1910121
X1915121
X1920121
X1935121
X1940121
X1945121
X1965121
X1970121
X1900121Y651956
X1905121
X1910121
X1915121
X1920121
X1925121
X1930121
X1935121
X1940121
X1945121
X1950121
X1965121
X1970121
X1900121Y656356
X1905121
X1910121
X1915121
X1920121
X1925121
X1930121
X1935121
X1940121
X1945121
X1950121
X1955121
X1960121
X1965121
X1970121
X1900121Y660756
X1905121
X1910121
X1915121
X1920121
X1925121
X1930121
X1935121
X1940121
X1945121
X1950121
X1955121
X1960121
X1965121
X1970121
T06
X677165Y-7874
X1405512
X1854331
Y610630
X1405512
X677165
X0
T07
X1629039Y565118
X1623134Y567874
X1626087Y570630
X1629039Y580079
X1623134Y582835
X1626087Y585591
X1629039Y595039
X1623134Y597795
X1626087Y600551
X1629039Y610000
X1623134Y612756
X1626087Y615512
X1634945
X1631992Y612756
X1637898Y610000
X1634945Y600551
X1631992Y597795
X1637898Y595039
X1634945Y585591
X1631992Y582835
X1637898Y580079
X1634945Y570630
X1631992Y567874
X1637898Y565118
X1646756
X1640850Y567874
X1643803Y570630
X1646756Y580079
X1640850Y582835
X1643803Y585591
X1646756Y595039
X1640850Y597795
X1643803Y600551
X1646756Y610000
X1640850Y612756
X1643803Y615512
X1673331
X1679236Y612756
X1670378
X1676283Y610000
X1673331Y600551
X1679236Y597795
X1670378
X1676283Y595039
X1673331Y585591
X1679236Y582835
X1670378
X1676283Y580079
X1673331Y570630
X1679236Y567874
X1670378
X1676283Y565118
X1685142
X1688094Y567874
X1682189Y570630
X1685142Y580079
X1688094Y582835
X1682189Y585591
X1685142Y595039
X1688094Y597795
X1682189Y600551
X1685142Y610000
X1688094Y612756
X1682189Y615512
X1691047
X1694000Y610000
X1691047Y600551
X1694000Y595039
X1691047Y585591
X1694000Y580079
X1691047Y570630
X1694000Y565118
T08
X28346Y101221
X23228Y109095
X22835Y101221
X17716Y109095
X11811Y101221
X6693Y109095
X6299Y101221
X1181Y109095
X-4725Y101221
X-9843Y109095
X-10236Y101221
X-15354Y109095
X-10236Y116969
X-4725
X6299
X11811
X22835
X28346
X23228Y124843
X17716
X6693
X1181
X-9843
X-15354
X-10236Y132717
X-4725
X6299
X11811
X22835
X28346
Y148465
X23228Y140591
X22835Y148465
X17716Y140591
X11811Y148465
X6693Y140591
X6299Y148465
X1181Y140591
X-4725Y148465
X-9843Y140591
X-10236Y148465
X-15354Y140591
Y156339
X-9843
X1181
X6693
X17716
X23228
X28346Y357362
X22835
X11811
X6299
X-4725
X-10236
X-15354Y365236
X-9843
X1181
X6693
X17716
X23228
X28346Y373110
X22835
X11811
X6299
X-4725
X-10236
X-15354Y380984
X-10236Y388858
X-9843Y380984
X-4725Y388858
X1181Y380984
X6299Y388858
X6693Y380984
X11811Y388858
X17716Y380984
X22835Y388858
X23228Y380984
X28346Y388858
X23228Y396732
X17716
X6693
X1181
X-9843
X-15354
X-10236Y404606
X-4725
X6299
X11811
X22835
X28346
X23228Y412480
X17716
X6693
X1181
X-9843
X-15354
T09
X83366Y215624
X85156Y212774
X87416Y215504
X87542Y210043
X89386Y212744
X91626Y215364
X95275Y217545
X95140Y220946
X91809Y221009
X88447Y221136
X85188Y221341
X72074Y243282
X68498Y243368
X65180
X61800Y243400
X49560Y644670
Y649570
Y649770
Y654670
X54360Y644670
Y654670
X210020Y644670
Y654670
X214820Y644670
Y649570
Y649770
Y654670
X238282Y644770
Y649670
Y649870
Y654770
X243082Y644770
Y654770
X397604Y644550
Y654550
X402404Y644550
Y649450
Y649650
Y654550
X425750Y644500
Y649400
Y649600
Y654500
X430550Y644500
Y654500
X585071Y644279
X585072Y644280
X585071Y654279
X585072Y654280
X589872Y644280
X589871Y644279
X589872Y649180
X589871Y649379
Y654279
X589872Y654280
X613298Y644231
Y649131
Y649331
Y654231
X618098Y644231
Y654231
X900715Y644259
Y654259
X905515Y644259
Y649159
Y649359
Y654259
X928952Y644220
Y649120
Y649320
Y654220
X933752Y644220
Y654220
X1214241Y644248
Y654248
X1219041Y644248
Y649148
Y649348
Y654248
X1242450Y644250
Y649150
Y649350
Y654250
X1247250Y644250
Y654250
X1527739Y644278
Y654278
X1532539Y644278
Y649178
Y649378
Y654278
T10
X1961890Y211043
Y238405
T11
X-15748Y101221
Y116969
X-4331Y109095
X787Y101221
Y116969
X12205Y109095
X17323Y101221
Y116969
X28740Y109095
X33858Y101221
Y116969
Y132717
X28740Y124843
X17323Y132717
X12205Y124843
X787Y132717
X-4331Y124843
X-15748Y132717
Y148465
X-4331Y140591
Y156339
X787Y148465
X12205Y140591
Y156339
X17323Y148465
X28740Y140591
Y156339
X33858Y148465
Y357362
X17323
X787
X-15748
Y373110
X-4331Y365236
X787Y373110
X12205Y365236
X17323Y373110
X28740Y365236
X33858Y373110
Y388858
X28740Y396732
Y380984
X17323Y388858
X12205Y396732
Y380984
X787Y388858
X-4331Y396732
Y380984
X-15748Y388858
Y404606
X-4331Y412480
X787Y404606
X12205Y412480
X17323Y404606
X28740Y412480
X33858Y404606
T12
X1741654Y536791
X1745591
X1749528
X1753465
X1757402
X1761339
T13
X72800Y105000
X77721
X82643
X87564
X92485
X97406
X102328
X107249
T14
X1687205Y536791
X1692205
X1697205
X1702205
X1707205
X1712205
X1717205
T15
X-11811Y204370
X-3937
X3937
X19685
X27559
X35433
Y227992
X27559
X19685
X3937
X-3937
X-11811
Y313504
X-3937
X3937
X19685
X27559
X35433
Y337126
X27559
X19685
X3937
X-3937
X-11811
T16
X28720Y244450
X22970Y244400
X17120Y244220
X12290Y264640
X18450Y267010
X24200Y267060
T17
X1892720Y525415
X1894689Y518328
X1904532
X1900595Y525415
X1908469
X1912406Y518328
X1916343Y525415
X1924217
X1922248Y518328
T18
X63093Y202300
X72936
X82779
X1914911Y495775
X1924754
X1934597
T19
X1851250Y561000
Y568874
Y576748
Y584622
T20
X1392264Y23976
X1513918
T21
X30500Y-42250
Y-52250
X40500
Y-42250
X50500
Y-52250
X60500
Y-42250
X70500
Y-52250
X80500
Y-42250
X90500
Y-52250
X100500
Y-42250
X110500
Y-52250
X120500
Y-42250
X130500
Y-52250
X140500
Y-42250
X457246Y-42301
Y-52301
X467246
Y-42301
X477246
Y-52301
X487246
Y-42301
X497246
Y-52301
X507246
Y-42301
X517246
Y-52301
X527246
Y-42301
X537246
Y-52301
X547246
Y-42301
X557246
Y-52301
X567246
Y-42301
X788984Y-42057
Y-52057
X798984
Y-42057
X808984
Y-52057
X818984
Y-42057
X828984
Y-52057
X838984
Y-42057
X848984
Y-52057
X858984
Y-42057
X868984
Y-52057
X878984
Y-42057
X888984
Y-52057
X898984
Y-42057
X1125583Y-42285
Y-52285
X1135583
Y-42285
X1145583
Y-52285
X1155583
Y-42285
X1382258Y-42257
Y-52257
X1392258
Y-42257
X1402258
Y-52257
X1412258
Y-42257
X1422258
Y-52257
X1432258
Y-42257
X1442258
Y-52257
X1452258
Y-42257
X1895945Y-2322
Y5670
Y13662
Y21654
Y29646
Y37638
Y45630
X1900945Y49626
Y41634
Y33642
Y25650
Y17658
Y9666
Y1674
Y-6318
T22
X1627642Y-14488
X1647327Y-315
X1667012Y-14488
T23
X1809665Y618663
X1819665
X1829665
T24
X1944882Y558464
Y566338
Y574212
Y582086
Y589960
Y597834
Y605708
X1952756
Y597834
Y589960
Y582086
Y574212
Y566338
Y558464
T25
X42724Y644656
Y644684
Y654656
Y654684
X67724
Y654656
Y644656
Y644684
X196656Y644656
Y644684
Y654684
Y654656
X221656Y654684
Y654656
Y644684
Y644656
X231446Y644756
Y644784
Y654756
Y654784
X256446
Y654756
Y644756
Y644784
X384240Y644536
Y644564
Y654536
Y654564
X409240
Y654536
Y644564
Y644536
X418914Y644486
Y644514
Y654514
Y654486
X443914
Y654514
Y644486
Y644514
X571707Y644293
X571708Y644266
Y654266
X571707Y654293
X596708Y654266
X596707Y654293
Y644293
X596708Y644266
X606462Y644245
Y644217
Y654217
Y654245
X631462
Y654217
Y644217
Y644245
X887351
Y644273
Y654245
Y654273
X912351
Y654245
Y644273
Y644245
X922116Y644206
Y644234
Y654206
Y654234
X947116Y654206
Y654234
Y644206
Y644234
X1200877
Y644262
Y654234
Y654262
X1225877
Y654234
Y644262
Y644234
X1235614Y644236
Y644264
Y654236
Y654264
X1260614
Y654236
Y644264
Y644236
X1514375Y644292
Y644264
Y654292
Y654264
X1539375
Y654292
Y644292
Y644264
T26
X1526871Y23968
X1881595
T27
X10512Y467244
X20512
X30512
X40512
X50512
X60512
X1884100Y493000
X1894100
X1904100
X1891086Y592105
Y602105
Y612105
T28
X-14488Y434094
X-4488
X5512
X15512
X89980Y145531
X99980
X109980
X119980
T29
X1442000Y-5000
Y-15000
X1452000
Y-5000
X1462000
Y-15000
X1472000
Y-5000
X1482000
Y-15000
X1492000
Y-5000
X1505000Y-15000
X1515000
X1525000
X1535000
X1545000
X1555000
X1565000
X1575000
X1703503
Y-5000
X1713503
Y-15000
X1723503
Y-5000
X1733503
Y-15000
X1743503
Y-5000
X1753503
Y-15000
X1769504
Y-5000
X1779504
Y-15000
X1789504
Y-5000
X1799504
Y-15000
X1809504
Y-5000
X1819504
Y-15000
T30
X94683Y-5822
Y13078
Y31978
Y50878
Y69778
Y88678
Y514079
Y532955
Y551879
Y570755
Y589679
Y608555
X637793
Y589679
Y570755
Y551879
Y532955
Y514079
Y88678
Y69778
Y50878
Y31978
Y13078
Y-5822
X744293
Y13078
Y31978
Y50878
Y69778
Y88678
Y514079
Y532955
Y551879
Y570755
Y589679
Y608555
X1287403
Y589679
Y570755
Y551879
Y532955
Y514079
Y88678
Y69778
Y50878
Y31978
Y13078
Y-5822
T31
X-1969Y178386
X18228
X44291
T32
X1613069Y302692
T33
X0Y0
T34
X1638131Y475946
Y525946
T35
X1956890Y237126
T36
X1956890Y211535
T37
X1628142Y240199
Y263999
T38
X1841929Y235430
X1724807Y451179
T39
X1969291Y486064
Y497874
T40
X1466693Y375787
X1572599Y505315
T41
X1854501Y195587
X1859854Y501441
Y525063
T42
X1800986Y523267
X1800985Y602503
T43
X1527844Y80791
T44
X99980Y136909
X-4488Y425472
T45
X1724606Y235430
X1930319Y451179
T46
X1401516Y23976
X1504666Y29882
T47
X638541Y171945
Y454425
X752641Y442425
Y159945
X1288068Y171945
Y454425
X1402168Y442425
Y159945
X1536123Y23968
X1872343Y29874
T48
X1712012Y195587
T49
X40512Y458744
T50
X1527844Y159531
T51
X1674921Y528523
Y545059
X1773347
Y528523
T52
X-7874Y216181
Y325315
T53
X-3937Y-43307
X-13780Y598560
X-3937Y646063
X1956693
Y-43307
T54
X1611283Y615236
Y567874
X1658528
X1705772
Y615236
T55
X133563Y183126
Y419626
X783171
Y183126
X1454685Y338189
X1600355Y527165
T56
X224410Y301378
X326772Y163582
Y439173
X500000
Y163582
X602362Y214764
Y387992
X874016Y301378
X976378Y163582
Y439173
X1149606
Y163582
X1251969Y214764
Y387992
M30
